FILE_TYPE = MACRO_DRAWING;
SET COLOR_WIRE YELLOW;
SET COLOR_PROP MONO;
SET COLOR_DOT WHITE;
SET COLOR_ARC YELLOW;
SET COLOR_BODY GREEN;
SET COLOR_NOTE MONO;
SET PROP_DISPLAY VALUE;
SET PAGE_NUMBER P240;
FORCEADD RES..2
R 2
(6425 1850);
FORCEPROP 1 LAST PART_NUMBER G21796-148
J 2
(6385 1725);
DISPLAY 0.617021 (6385 1725);
PAINT BLUE (6385 1725);
FORCEPROP 1 LAST WATTAGE 1/16W
J 2
(6385 1825);
DISPLAY 0.617021 (6385 1825);
PAINT SKYBLUE (6385 1825);
FORCEPROP 1 LAST MATERIAL CHIP
J 2
(6385 1775);
DISPLAY 0.617021 (6385 1775);
PAINT SKYBLUE (6385 1775);
FORCEPROP 1 LAST PACK_TYPE 0402
J 2
(6385 1675);
DISPLAY 0.617021 (6385 1675);
PAINT SKYBLUE (6385 1675);
FORCEPROP 1 LAST TOLERANCE 1%
J 2
(6380 1875);
DISPLAY 0.617021 (6380 1875);
PAINT SKYBLUE (6380 1875);
FORCEPROP 1 LAST VALUE 64.9K
J 2
(6380 1925);
DISPLAY 0.617021 (6380 1925);
PAINT SKYBLUE (6380 1925);
FORCEPROP 1 LAST LOCATION R8F9
J 2
(6380 1975);
DISPLAY 0.617021 (6380 1975);
PAINT AQUA (6380 1975);
FORCEPROP 1 LASTPIN (6425 1950) $PN 1
J 2
(6420 1912);
DISPLAY 0.617021 (6420 1912);
PAINT WHITE (6420 1912);
FORCEPROP 1 LASTPIN (6425 1750) $PN 2
J 2
(6420 1760);
DISPLAY 0.617021 (6420 1760);
PAINT WHITE (6420 1760);
FORCEPROP 2 LAST CDS_LOCATION R8F9
J 2
(6380 1975);
DISPLAY 0.617021 (6380 1975);
PAINT AQUA (6380 1975);
DISPLAY INVISIBLE (6380 1975);
FORCEPROP 2 LAST ROOM P3V3_STBY_VR
J 2
(6425 1850);
PAINT GREEN (6425 1850);
DISPLAY INVISIBLE (6425 1850);
FORCEPROP 2 LAST BOM_COST P3V3_STBY_VR
J 2
(6425 1850);
PAINT WHITE (6425 1850);
DISPLAY INVISIBLE (6425 1850);
FORCEPROP 2 LAST CDS_LIB mstr_discrete
J 2
(6425 1850);
PAINT MONO (6425 1850);
DISPLAY INVISIBLE (6425 1850);
FORCEPROP 1 LAST PATH I106
J 2
(6375 2025);
DISPLAY 0.978723 (6375 2025);
PAINT WHITE (6375 2025);
DISPLAY INVISIBLE (6375 2025);
FORCEPROP 2 LAST SEC 1
J 0
(6375 2075);
DISPLAY 0.680851 (6375 2075);
PAINT MONO (6375 2075);
DISPLAY INVISIBLE (6375 2075);
FORCEPROP 2 LAST SEC_TYPE 0402
J 0
(6375 2075);
DISPLAY 1.021277 (6375 2075);
PAINT ORANGE (6375 2075);
DISPLAY INVISIBLE (6375 2075);
FORCEADD OFFPAGE..1
(5175 2725);
FORCEPROP 2 LAST $XR0 241 
J 0
(4923 2725);
DISPLAY 0.638298 (4923 2725);
PAINT MONO (4923 2725);
FORCEPROP 2 LAST PATH I107
J 0
(4925 2775);
DISPLAY 1.021277 (4925 2775);
PAINT ORANGE (4925 2775);
DISPLAY INVISIBLE (4925 2775);
FORCEPROP 2 LAST BOM_COST PVPP_KLM_VR
J 0
(4350 2800);
DISPLAY 1.042553 (4350 2800);
PAINT WHITE (4350 2800);
DISPLAY INVISIBLE (4350 2800);
FORCEPROP 2 LAST ROOM PVPP_KLM_VR
J 0
(4625 2800);
DISPLAY 1.042553 (4625 2800);
PAINT GREEN (4625 2800);
DISPLAY INVISIBLE (4625 2800);
FORCEPROP 0 LAST TOLERANCE 1%
J 0
(5225 2800);
PAINT SKYBLUE (5225 2800);
DISPLAY INVISIBLE (5225 2800);
FORCEPROP 1 LAST COMMENT_BODY TRUE
J 0
(5300 2625);
DISPLAY 0.872340 (5300 2625);
PAINT PEACH (5300 2625);
DISPLAY INVISIBLE (5300 2625);
FORCEPROP 2 LAST CDS_LIB mstr_standard
J 0
(5175 2725);
PAINT MONO (5175 2725);
DISPLAY INVISIBLE (5175 2725);
FORCEPROP 1 LAST OFFPAGE TRUE
J 0
(5500 2600);
PAINT GREEN (5500 2600);
DISPLAY INVISIBLE (5500 2600);
FORCEADD CAP..1
R 2
(5600 3300);
FORCEPROP 1 LAST PART_NUMBER E15431-003
J 2
(5550 3150);
DISPLAY 0.617021 (5550 3150);
PAINT BLUE (5550 3150);
FORCEPROP 1 LASTPIN (5600 3200) $PN 2
J 2
(5590 3180);
DISPLAY 0.617021 (5590 3180);
PAINT ORANGE (5590 3180);
FORCEPROP 1 LAST MATERIAL X6S
J 2
(5550 3200);
DISPLAY 0.617021 (5550 3200);
PAINT SKYBLUE (5550 3200);
FORCEPROP 1 LAST VOLTAGE 6.3V
J 2
(5550 3300);
DISPLAY 0.617021 (5550 3300);
PAINT SKYBLUE (5550 3300);
FORCEPROP 1 LAST PACK_TYPE 0603
J 2
(5550 3100);
DISPLAY 0.617021 (5550 3100);
PAINT SKYBLUE (5550 3100);
FORCEPROP 1 LAST TOLERANCE 10%
J 2
(5550 3250);
DISPLAY 0.617021 (5550 3250);
PAINT SKYBLUE (5550 3250);
FORCEPROP 1 LASTPIN (5600 3400) $PN 1
J 2
(5590 3380);
DISPLAY 0.617021 (5590 3380);
PAINT ORANGE (5590 3380);
FORCEPROP 1 LAST VALUE 4.7UF
J 2
(5550 3350);
DISPLAY 0.617021 (5550 3350);
PAINT SKYBLUE (5550 3350);
FORCEPROP 1 LAST LOCATION C2R11
J 2
(5550 3400);
DISPLAY 0.617021 (5550 3400);
PAINT AQUA (5550 3400);
FORCEPROP 2 LAST CDS_LIB mstr_discrete
J 0
(5600 3300);
PAINT ORANGE (5600 3300);
DISPLAY INVISIBLE (5600 3300);
FORCEPROP 2 LAST REUSE_ID 20
J 0
(5550 3500);
DISPLAY 1.042553 (5550 3500);
PAINT ORANGE (5550 3500);
DISPLAY INVISIBLE (5550 3500);
FORCEPROP 2 LAST SEC_TYPE 0603
J 0
(5550 3500);
DISPLAY 1.021277 (5550 3500);
PAINT ORANGE (5550 3500);
DISPLAY INVISIBLE (5550 3500);
FORCEPROP 2 LAST BOM_COST P3V3_STBY_VR
J 2
(5550 3500);
DISPLAY 1.042553 (5550 3500);
PAINT WHITE (5550 3500);
DISPLAY INVISIBLE (5550 3500);
FORCEPROP 2 LAST SEC 1
J 0
(5550 3500);
DISPLAY 0.680851 (5550 3500);
PAINT MONO (5550 3500);
DISPLAY INVISIBLE (5550 3500);
FORCEPROP 2 LAST CDS_LOCATION C2R11
J 2
(5550 3400);
DISPLAY 0.617021 (5550 3400);
PAINT AQUA (5550 3400);
DISPLAY INVISIBLE (5550 3400);
FORCEPROP 1 LAST PATH I109
J 2
(5550 3450);
DISPLAY 0.978723 (5550 3450);
PAINT WHITE (5550 3450);
DISPLAY INVISIBLE (5550 3450);
FORCEPROP 2 LAST ROOM P3V3_STBY_VR
J 2
(5550 3600);
DISPLAY 1.042553 (5550 3600);
PAINT GREEN (5550 3600);
DISPLAY INVISIBLE (5550 3600);
FORCEADD GND..1
(5625 2150);
FORCEPROP 3 LASTPIN (5625 2200) SIG_NAME GND\g
J 0
(5635 2210);
DISPLAY 0.659574 (5635 2210);
PAINT MONO (5635 2210);
DISPLAY INVISIBLE (5635 2210);
FORCEPROP 2 LAST ROOM PVPP_KLM_VR
J 0
(4875 2225);
DISPLAY 1.042553 (4875 2225);
PAINT GREEN (4875 2225);
DISPLAY INVISIBLE (4875 2225);
FORCEPROP 2 LAST BOM_COST PVPP_KLM_VR
J 0
(4875 2275);
DISPLAY 1.042553 (4875 2275);
PAINT WHITE (4875 2275);
DISPLAY INVISIBLE (4875 2275);
FORCEPROP 2 LAST BOM SYSB_CPLD
J 0
(4875 2325);
DISPLAY 1.042553 (4875 2325);
PAINT ORANGE (4875 2325);
DISPLAY INVISIBLE (4875 2325);
FORCEPROP 1 LAST BODY_TYPE PLUMBING
J 0
(5580 2107);
DISPLAY 0.340426 (5580 2107);
PAINT GREEN (5580 2107);
DISPLAY INVISIBLE (5580 2107);
FORCEPROP 2 LAST CDS_LIB mstr_symbols
J 0
(5625 2150);
PAINT MONO (5625 2150);
DISPLAY INVISIBLE (5625 2150);
FORCEPROP 1 LAST VOLTAGE 0
J 0
(5625 2150);
PAINT SKYBLUE (5625 2150);
DISPLAY INVISIBLE (5625 2150);
FORCEPROP 1 LAST HDL_POWER GND
J 0
(5625 2300);
DISPLAY 0.680851 (5625 2300);
PAINT GREEN (5625 2300);
DISPLAY INVISIBLE (5625 2300);
FORCEPROP 1 LAST PATH I110
J 0
(5700 2150);
DISPLAY 0.872340 (5700 2150);
PAINT AQUA (5700 2150);
DISPLAY INVISIBLE (5700 2150);
FORCEPROP 1 LAST SIZE 1B
J 0
(5700 2100);
DISPLAY 0.680851 (5700 2100);
PAINT ORANGE (5700 2100);
DISPLAY INVISIBLE (5700 2100);
FORCEADD RES..2
(5625 2400);
FORCEPROP 1 LASTPIN (5625 2500) $PN 1
J 0
(5630 2462);
DISPLAY 0.617021 (5630 2462);
PAINT WHITE (5630 2462);
FORCEPROP 1 LASTPIN (5625 2300) $PN 2
J 0
(5630 2310);
DISPLAY 0.617021 (5630 2310);
PAINT WHITE (5630 2310);
FORCEPROP 1 LAST PACK_TYPE 0402
J 0
(5665 2225);
DISPLAY 0.617021 (5665 2225);
PAINT SKYBLUE (5665 2225);
FORCEPROP 1 LAST TOLERANCE 1%
J 0
(5670 2425);
DISPLAY 0.617021 (5670 2425);
PAINT SKYBLUE (5670 2425);
FORCEPROP 1 LAST WATTAGE 1/16W
J 0
(5665 2375);
DISPLAY 0.617021 (5665 2375);
PAINT SKYBLUE (5665 2375);
FORCEPROP 1 LAST VALUE 10.0K
J 0
(5670 2475);
DISPLAY 0.617021 (5670 2475);
PAINT SKYBLUE (5670 2475);
FORCEPROP 1 LAST LOCATION R8F1
J 0
(5670 2525);
DISPLAY 0.617021 (5670 2525);
PAINT AQUA (5670 2525);
FORCEPROP 1 LAST MATERIAL EMPTY
J 0
(5665 2325);
DISPLAY 0.617021 (5665 2325);
PAINT RED (5665 2325);
FORCEPROP 1 LAST PART_NUMBER G21796-016
J 0
(5640 2275);
DISPLAY 0.617021 (5640 2275);
PAINT BLUE (5640 2275);
FORCEPROP 2 LAST CDS_LIB mstr_discrete
J 0
(5625 2400);
PAINT MONO (5625 2400);
DISPLAY INVISIBLE (5625 2400);
FORCEPROP 2 LAST CDS_LOCATION R8F1
J 0
(5670 2525);
DISPLAY 0.617021 (5670 2525);
PAINT AQUA (5670 2525);
DISPLAY INVISIBLE (5670 2525);
FORCEPROP 2 LAST ROOM P3V3_STBY_VR
J 0
(5675 2625);
DISPLAY 1.042553 (5675 2625);
PAINT GREEN (5675 2625);
DISPLAY INVISIBLE (5675 2625);
FORCEPROP 1 LAST PATH I111
J 0
(5675 2575);
DISPLAY 0.978723 (5675 2575);
PAINT WHITE (5675 2575);
DISPLAY INVISIBLE (5675 2575);
FORCEPROP 2 LAST $SEC 1
J 0
(5675 2625);
DISPLAY 0.680851 (5675 2625);
PAINT MONO (5675 2625);
DISPLAY INVISIBLE (5675 2625);
FORCEPROP 2 LAST CDS_SEC 1
J 0
(5675 2625);
DISPLAY 1.042553 (5675 2625);
PAINT ORANGE (5675 2625);
DISPLAY INVISIBLE (5675 2625);
FORCEPROP 0 LAST BOM SYSB_CPLD
J 0
(5675 2725);
DISPLAY 1.042553 (5675 2725);
PAINT ORANGE (5675 2725);
DISPLAY INVISIBLE (5675 2725);
FORCEPROP 2 LAST BOM_COST P3V3_STBY_VR
J 0
(5675 2625);
DISPLAY 1.042553 (5675 2625);
PAINT WHITE (5675 2625);
DISPLAY INVISIBLE (5675 2625);
FORCEADD CAP..1
R 2
(6175 2475);
FORCEPROP 1 LAST PACK_TYPE 0402LF
J 2
(6125 2275);
DISPLAY 0.617021 (6125 2275);
PAINT SKYBLUE (6125 2275);
FORCEPROP 1 LAST VALUE 1000PF
J 2
(6125 2525);
DISPLAY 0.617021 (6125 2525);
PAINT SKYBLUE (6125 2525);
FORCEPROP 1 LAST MATERIAL EMPTY
J 2
(6125 2375);
DISPLAY 0.617021 (6125 2375);
PAINT RED (6125 2375);
FORCEPROP 1 LAST TOLERANCE 10%
J 2
(6125 2425);
DISPLAY 0.617021 (6125 2425);
PAINT SKYBLUE (6125 2425);
FORCEPROP 1 LAST VOLTAGE 50V
J 2
(6125 2475);
DISPLAY 0.617021 (6125 2475);
PAINT SKYBLUE (6125 2475);
FORCEPROP 1 LAST LOCATION C8E17
J 2
(6125 2575);
DISPLAY 0.617021 (6125 2575);
PAINT AQUA (6125 2575);
FORCEPROP 1 LASTPIN (6175 2575) $PN 1
J 2
(6165 2555);
DISPLAY 0.617021 (6165 2555);
PAINT WHITE (6165 2555);
FORCEPROP 1 LASTPIN (6175 2375) $PN 2
J 2
(6165 2355);
DISPLAY 0.617021 (6165 2355);
PAINT WHITE (6165 2355);
FORCEPROP 1 LAST PART_NUMBER A36096-046
J 2
(6150 2325);
DISPLAY 0.617021 (6150 2325);
PAINT BLUE (6150 2325);
FORCEPROP 1 LAST PATH I113
J 2
(6125 2625);
DISPLAY 0.978723 (6125 2625);
PAINT WHITE (6125 2625);
DISPLAY INVISIBLE (6125 2625);
FORCEPROP 2 LAST CDS_LOCATION C8E17
J 2
(6125 2575);
DISPLAY 0.617021 (6125 2575);
PAINT AQUA (6125 2575);
DISPLAY INVISIBLE (6125 2575);
FORCEPROP 2 LAST $SEC 1
J 2
(6125 2675);
DISPLAY 0.680851 (6125 2675);
PAINT MONO (6125 2675);
DISPLAY INVISIBLE (6125 2675);
FORCEPROP 2 LAST CDS_SEC 1
J 2
(6125 2675);
DISPLAY 1.042553 (6125 2675);
PAINT ORANGE (6125 2675);
DISPLAY INVISIBLE (6125 2675);
FORCEPROP 0 LAST REUSE_ID 1
J 2
(6125 2675);
DISPLAY 1.042553 (6125 2675);
PAINT ORANGE (6125 2675);
DISPLAY INVISIBLE (6125 2675);
FORCEPROP 0 LAST FIN VR_1P2
J 2
(6125 2775);
PAINT ORANGE (6125 2775);
DISPLAY INVISIBLE (6125 2775);
FORCEPROP 2 LAST ROOM P3V3_STBY_VR
J 2
(6175 2475);
PAINT GREEN (6175 2475);
DISPLAY INVISIBLE (6175 2475);
FORCEPROP 2 LAST CDS_LIB mstr_discrete
J 2
(6175 2475);
PAINT MONO (6175 2475);
DISPLAY INVISIBLE (6175 2475);
FORCEPROP 2 LAST BOM_COST P3V3_STBY_VR
J 2
(6175 2475);
PAINT WHITE (6175 2475);
DISPLAY INVISIBLE (6175 2475);
FORCEADD P5V_STBY..1
(5725 3600);
FORCEPROP 3 LASTPIN (5725 3550) SIG_NAME P5V_STBY\g
J 0
(5735 3560);
DISPLAY 0.659574 (5735 3560);
PAINT MONO (5735 3560);
DISPLAY INVISIBLE (5735 3560);
FORCEPROP 1 LAST HDL_POWER P5V_STBY
J 0
(5425 3475);
DISPLAY 0.872340 (5425 3475);
PAINT ORANGE (5425 3475);
DISPLAY INVISIBLE (5425 3475);
FORCEPROP 1 LAST BODY_TYPE PLUMBING
J 0
(5680 3557);
DISPLAY 0.340426 (5680 3557);
PAINT GREEN (5680 3557);
DISPLAY INVISIBLE (5680 3557);
FORCEPROP 1 LAST VOLTAGE +5.0V
J 0
(5925 3750);
DISPLAY 1.021277 (5925 3750);
PAINT SKYBLUE (5925 3750);
DISPLAY INVISIBLE (5925 3750);
FORCEPROP 2 LAST CDS_LIB mstr_symbols
J 0
(5725 3600);
PAINT MONO (5725 3600);
DISPLAY INVISIBLE (5725 3600);
FORCEPROP 1 LAST SIZE 1B
J 0
(5770 3622);
DISPLAY 0.340426 (5770 3622);
PAINT GREEN (5770 3622);
DISPLAY INVISIBLE (5770 3622);
FORCEPROP 1 LAST PATH I114
J 0
(5770 3602);
DISPLAY 0.340426 (5770 3602);
PAINT GREEN (5770 3602);
DISPLAY INVISIBLE (5770 3602);
FORCEADD GND..1
(6350 3100);
FORCEPROP 3 LASTPIN (6350 3150) SIG_NAME GND\g
J 0
(6360 3160);
DISPLAY 0.659574 (6360 3160);
PAINT MONO (6360 3160);
DISPLAY INVISIBLE (6360 3160);
FORCEPROP 2 LAST BOM_COST PVPP_KLM_VR
J 0
(5450 3250);
DISPLAY 1.042553 (5450 3250);
PAINT WHITE (5450 3250);
DISPLAY INVISIBLE (5450 3250);
FORCEPROP 2 LAST ROOM PVPP_KLM_VR
J 0
(5700 3250);
PAINT GREEN (5700 3250);
DISPLAY INVISIBLE (5700 3250);
FORCEPROP 1 LAST BODY_TYPE PLUMBING
J 0
(6305 3057);
DISPLAY 0.340426 (6305 3057);
PAINT GREEN (6305 3057);
DISPLAY INVISIBLE (6305 3057);
FORCEPROP 2 LAST CDS_LIB mstr_symbols
J 0
(6350 3175);
PAINT MONO (6350 3175);
DISPLAY INVISIBLE (6350 3175);
FORCEPROP 1 LAST VOLTAGE 0
J 0
(6350 3175);
PAINT SKYBLUE (6350 3175);
DISPLAY INVISIBLE (6350 3175);
FORCEPROP 1 LAST HDL_POWER GND
J 0
(6350 3325);
DISPLAY 0.893617 (6350 3325);
PAINT GREEN (6350 3325);
DISPLAY INVISIBLE (6350 3325);
FORCEPROP 1 LAST PATH I115
J 0
(6425 3100);
DISPLAY 0.872340 (6425 3100);
PAINT AQUA (6425 3100);
DISPLAY INVISIBLE (6425 3100);
FORCEPROP 1 LAST SIZE 1B
J 0
(6425 3125);
DISPLAY 0.893617 (6425 3125);
PAINT GREEN (6425 3125);
DISPLAY INVISIBLE (6425 3125);
FORCEADD CAP..1
(6350 3350);
FORCEPROP 1 LASTPIN (6350 3250) $PN 2
J 0
(6360 3230);
DISPLAY 0.617021 (6360 3230);
PAINT WHITE (6360 3230);
FORCEPROP 1 LASTPIN (6350 3450) $PN 1
J 0
(6360 3430);
DISPLAY 0.617021 (6360 3430);
PAINT WHITE (6360 3430);
FORCEPROP 1 LAST MATERIAL X7R
J 0
(6400 3250);
DISPLAY 0.617021 (6400 3250);
PAINT SKYBLUE (6400 3250);
FORCEPROP 1 LAST VOLTAGE 50V
J 0
(6400 3350);
DISPLAY 0.617021 (6400 3350);
PAINT SKYBLUE (6400 3350);
FORCEPROP 1 LAST PACK_TYPE 0402LF
J 0
(6400 3200);
DISPLAY 0.617021 (6400 3200);
PAINT SKYBLUE (6400 3200);
FORCEPROP 1 LAST TOLERANCE 10%
J 0
(6400 3300);
DISPLAY 0.617021 (6400 3300);
PAINT SKYBLUE (6400 3300);
FORCEPROP 1 LAST LOCATION C8F2
J 0
(6400 3450);
DISPLAY 0.617021 (6400 3450);
PAINT AQUA (6400 3450);
FORCEPROP 1 LAST VALUE 1000PF
J 0
(6400 3400);
DISPLAY 0.617021 (6400 3400);
PAINT SKYBLUE (6400 3400);
FORCEPROP 1 LAST PART_NUMBER A36096-046
J 0
(6400 3150);
DISPLAY 0.617021 (6400 3150);
PAINT BLUE (6400 3150);
FORCEPROP 2 LAST BOM_COST P3V3_STBY_VR
J 0
(6350 3350);
PAINT WHITE (6350 3350);
DISPLAY INVISIBLE (6350 3350);
FORCEPROP 2 LAST CDS_LIB mstr_discrete
J 2
(6350 3350);
PAINT MONO (6350 3350);
DISPLAY INVISIBLE (6350 3350);
FORCEPROP 2 LAST ROOM P3V3_STBY_VR
J 0
(6350 3350);
PAINT GREEN (6350 3350);
DISPLAY INVISIBLE (6350 3350);
FORCEPROP 2 LAST $SEC 1
J 2
(6400 3550);
DISPLAY 0.680851 (6400 3550);
PAINT MONO (6400 3550);
DISPLAY INVISIBLE (6400 3550);
FORCEPROP 2 LAST CDS_LOCATION C8F2
J 0
(6400 3450);
DISPLAY 0.617021 (6400 3450);
PAINT AQUA (6400 3450);
DISPLAY INVISIBLE (6400 3450);
FORCEPROP 1 LAST PATH I116
J 0
(6400 3500);
DISPLAY 0.978723 (6400 3500);
PAINT WHITE (6400 3500);
DISPLAY INVISIBLE (6400 3500);
FORCEPROP 2 LAST CDS_SEC 1
J 2
(6400 3550);
DISPLAY 1.042553 (6400 3550);
PAINT ORANGE (6400 3550);
DISPLAY INVISIBLE (6400 3550);
FORCEPROP 2 LAST REUSE_ID 17
J 0
(6400 3550);
DISPLAY 1.042553 (6400 3550);
PAINT ORANGE (6400 3550);
DISPLAY INVISIBLE (6400 3550);
FORCEADD RES..2
R 2
(6275 3900);
FORCEPROP 1 LAST WATTAGE 1/16W
J 2
(6235 3875);
DISPLAY 0.617021 (6235 3875);
PAINT SKYBLUE (6235 3875);
FORCEPROP 1 LAST MATERIAL CHIP
J 2
(6235 3825);
DISPLAY 0.617021 (6235 3825);
PAINT SKYBLUE (6235 3825);
FORCEPROP 1 LAST PACK_TYPE 0402
J 2
(6235 3725);
DISPLAY 0.617021 (6235 3725);
PAINT SKYBLUE (6235 3725);
FORCEPROP 1 LAST VALUE 1.00K
J 2
(6230 3975);
DISPLAY 0.617021 (6230 3975);
PAINT SKYBLUE (6230 3975);
FORCEPROP 1 LAST PART_NUMBER G21796-026
J 2
(6235 3775);
DISPLAY 0.617021 (6235 3775);
PAINT BLUE (6235 3775);
FORCEPROP 1 LAST LOCATION R8F5
J 2
(6230 4025);
DISPLAY 0.617021 (6230 4025);
PAINT AQUA (6230 4025);
FORCEPROP 1 LASTPIN (6275 3800) $PN 2
J 2
(6270 3810);
DISPLAY 0.617021 (6270 3810);
PAINT WHITE (6270 3810);
FORCEPROP 1 LASTPIN (6275 4000) $PN 1
J 2
(6270 3962);
DISPLAY 0.617021 (6270 3962);
PAINT WHITE (6270 3962);
FORCEPROP 1 LAST TOLERANCE 1%
J 2
(6230 3925);
DISPLAY 0.617021 (6230 3925);
PAINT SKYBLUE (6230 3925);
FORCEPROP 2 LAST CDS_LOCATION R8F5
J 2
(6230 4025);
DISPLAY 0.617021 (6230 4025);
PAINT AQUA (6230 4025);
DISPLAY INVISIBLE (6230 4025);
FORCEPROP 2 LAST CDS_LIB mstr_discrete
J 2
(6275 3900);
PAINT MONO (6275 3900);
DISPLAY INVISIBLE (6275 3900);
FORCEPROP 2 LAST ROOM PVPP_KLM_VR
J 2
(6215 4065);
PAINT GREEN (6215 4065);
DISPLAY INVISIBLE (6215 4065);
FORCEPROP 1 LAST PATH I117
J 2
(6225 4075);
DISPLAY 0.978723 (6225 4075);
PAINT WHITE (6225 4075);
DISPLAY INVISIBLE (6225 4075);
FORCEPROP 2 LAST BOM_COST P3V3_STBY_VR
J 2
(6215 4090);
DISPLAY 1.042553 (6215 4090);
PAINT WHITE (6215 4090);
DISPLAY INVISIBLE (6215 4090);
FORCEPROP 2 LAST SEC 1
J 2
(6225 4125);
DISPLAY 0.680851 (6225 4125);
PAINT MONO (6225 4125);
DISPLAY INVISIBLE (6225 4125);
FORCEPROP 2 LAST REUSE_ID 21
J 2
(6225 4125);
DISPLAY 1.042553 (6225 4125);
PAINT ORANGE (6225 4125);
DISPLAY INVISIBLE (6225 4125);
FORCEPROP 2 LAST SEC_TYPE 0402
J 2
(6225 4125);
DISPLAY 1.042553 (6225 4125);
PAINT ORANGE (6225 4125);
DISPLAY INVISIBLE (6225 4125);
FORCEADD RT8240..1
(7550 2625);
FORCEPROP 2 LASTPIN (7150 2425) $PN 13
J 2
(7140 2435);
DISPLAY 0.617021 (7140 2435);
PAINT ORANGE (7140 2435);
FORCEPROP 2 LASTPIN (7150 2375) $PN 12
J 2
(7140 2385);
DISPLAY 0.617021 (7140 2385);
PAINT ORANGE (7140 2385);
FORCEPROP 2 LASTPIN (7150 2325) $PN 10
J 2
(7140 2335);
DISPLAY 0.617021 (7140 2335);
PAINT ORANGE (7140 2335);
FORCEPROP 2 LASTPIN (7150 2675) $PN 11
J 2
(7140 2685);
DISPLAY 0.617021 (7140 2685);
PAINT ORANGE (7140 2685);
FORCEPROP 2 LASTPIN (7150 2725) $PN 8
J 2
(7140 2735);
DISPLAY 0.617021 (7140 2735);
PAINT ORANGE (7140 2735);
FORCEPROP 2 LASTPIN (7150 2825) $PN 9
J 2
(7140 2835);
DISPLAY 0.617021 (7140 2835);
PAINT ORANGE (7140 2835);
FORCEPROP 2 LASTPIN (7150 2875) $PN 5
J 2
(7140 2885);
DISPLAY 0.617021 (7140 2885);
PAINT ORANGE (7140 2885);
FORCEPROP 1 LAST PART_NUMBER H66262-001
J 0
(7200 2175);
DISPLAY 0.617021 (7200 2175);
PAINT BLUE (7200 2175);
FORCEPROP 2 LASTPIN (7950 2375) $PN 7
J 0
(7960 2385);
DISPLAY 0.617021 (7960 2385);
PAINT ORANGE (7960 2385);
FORCEPROP 2 LASTPIN (7950 2475) $PN 6
J 0
(7960 2485);
DISPLAY 0.617021 (7960 2485);
PAINT ORANGE (7960 2485);
FORCEPROP 2 LASTPIN (7950 2775) $PN 3
J 0
(7960 2785);
DISPLAY 0.617021 (7960 2785);
PAINT ORANGE (7960 2785);
FORCEPROP 2 LASTPIN (7950 2675) $PN 2
J 0
(7960 2685);
DISPLAY 0.617021 (7960 2685);
PAINT ORANGE (7960 2685);
FORCEPROP 2 LASTPIN (7950 2575) $PN 1
J 0
(7960 2585);
DISPLAY 0.617021 (7960 2585);
PAINT ORANGE (7960 2585);
FORCEPROP 2 LASTPIN (7950 2875) $PN 4
J 0
(7960 2885);
DISPLAY 0.617021 (7960 2885);
PAINT ORANGE (7960 2885);
FORCEPROP 1 LAST MATERIAL IC
J 0
(7200 3075);
DISPLAY 0.617021 (7200 3075);
PAINT SKYBLUE (7200 3075);
FORCEPROP 1 LAST LOCATION EU8F1
J 0
(7200 3125);
DISPLAY 0.617021 (7200 3125);
PAINT AQUA (7200 3125);
FORCEPROP 2 LAST CDS_LIB mstr_vreg
J 0
(7550 2625);
PAINT MONO (7550 2625);
DISPLAY INVISIBLE (7550 2625);
FORCEPROP 0 LAST ROOM P3V3_STBY_VR
J 0
(7200 3225);
DISPLAY 1.021277 (7200 3225);
PAINT ORANGE (7200 3225);
DISPLAY INVISIBLE (7200 3225);
FORCEPROP 2 LAST CDS_LOCATION EU8F1
J 0
(7200 3125);
DISPLAY 0.617021 (7200 3125);
PAINT AQUA (7200 3125);
DISPLAY INVISIBLE (7200 3125);
FORCEPROP 2 LAST SEC 1
J 0
(7200 3175);
DISPLAY 0.680851 (7200 3175);
PAINT MONO (7200 3175);
DISPLAY INVISIBLE (7200 3175);
FORCEPROP 2 LAST SEC_TYPE QFN
J 0
(7200 3175);
DISPLAY 1.021277 (7200 3175);
PAINT ORANGE (7200 3175);
DISPLAY INVISIBLE (7200 3175);
FORCEPROP 1 LAST PACK_TYPE QFN
J 0
(7200 3175);
PAINT SKYBLUE (7200 3175);
DISPLAY INVISIBLE (7200 3175);
FORCEPROP 1 LAST PATH I125
J 0
(7600 3075);
PAINT GREEN (7600 3075);
DISPLAY INVISIBLE (7600 3075);
FORCEADD OFFPAGE..2
(7825 3825);
FORCEPROP 2 LAST $XR0 101 
J 0
(8014 3825);
DISPLAY 0.638298 (8014 3825);
PAINT MONO (8014 3825);
FORCEPROP 2 LAST $XR1 189 
J 0
(8134 3825);
DISPLAY 0.638298 (8134 3825);
PAINT MONO (8134 3825);
FORCEPROP 2 LAST $XR2 191 
J 0
(8254 3825);
DISPLAY 0.638298 (8254 3825);
PAINT MONO (8254 3825);
FORCEPROP 2 LAST $XR3 196 
J 0
(8014 3789);
DISPLAY 0.638298 (8014 3789);
PAINT MONO (8014 3789);
FORCEPROP 2 LAST $XR4 237 
J 0
(8134 3789);
DISPLAY 0.638298 (8134 3789);
PAINT MONO (8134 3789);
FORCEPROP 2 LAST $XR5 239 
J 0
(8254 3789);
DISPLAY 0.638298 (8254 3789);
PAINT MONO (8254 3789);
FORCEPROP 2 LAST BOM_COST PVPP_KLM_VR
J 0
(7125 3900);
DISPLAY 1.042553 (7125 3900);
PAINT WHITE (7125 3900);
DISPLAY INVISIBLE (7125 3900);
FORCEPROP 2 LAST ROOM PVPP_KLM_VR
J 0
(7400 3900);
DISPLAY 1.042553 (7400 3900);
PAINT GREEN (7400 3900);
DISPLAY INVISIBLE (7400 3900);
FORCEPROP 1 LAST COMMENT_BODY TRUE
J 0
(7780 3730);
DISPLAY 0.872340 (7780 3730);
PAINT PEACH (7780 3730);
DISPLAY INVISIBLE (7780 3730);
FORCEPROP 2 LAST CDS_LIB mstr_standard
J 2
(7825 3825);
PAINT MONO (7825 3825);
DISPLAY INVISIBLE (7825 3825);
FORCEPROP 1 LAST OFFPAGE TRUE
J 0
(8150 3700);
PAINT GREEN (8150 3700);
DISPLAY INVISIBLE (8150 3700);
FORCEPROP 0 LAST TOLERANCE 1%
J 0
(8000 3900);
PAINT SKYBLUE (8000 3900);
DISPLAY INVISIBLE (8000 3900);
FORCEPROP 2 LAST PATH I126
J 0
(8025 3875);
DISPLAY 1.021277 (8025 3875);
PAINT ORANGE (8025 3875);
DISPLAY INVISIBLE (8025 3875);
FORCEADD RES..1
(7600 3425);
FORCEPROP 1 LAST VALUE 0.0
J 2
(7500 3300);
DISPLAY 0.617021 (7500 3300);
PAINT SKYBLUE (7500 3300);
FORCEPROP 1 LAST WATTAGE 1/16W
J 2
(7575 3250);
DISPLAY 0.617021 (7575 3250);
PAINT SKYBLUE (7575 3250);
FORCEPROP 1 LAST TOLERANCE 5%
J 0
(7550 3300);
DISPLAY 0.617021 (7550 3300);
PAINT SKYBLUE (7550 3300);
FORCEPROP 1 LASTPIN (7500 3425) $PN 1
J 0
(7512 3437);
DISPLAY 0.617021 (7512 3437);
PAINT WHITE (7512 3437);
FORCEPROP 1 LASTPIN (7700 3425) $PN 2
J 0
(7662 3437);
DISPLAY 0.617021 (7662 3437);
PAINT WHITE (7662 3437);
FORCEPROP 1 LAST MATERIAL CHIP
J 0
(7600 3250);
DISPLAY 0.617021 (7600 3250);
PAINT SKYBLUE (7600 3250);
FORCEPROP 1 LAST PACK_TYPE 0402
J 0
(7650 3300);
DISPLAY 0.617021 (7650 3300);
PAINT SKYBLUE (7650 3300);
FORCEPROP 1 LAST PART_NUMBER G21497-005
J 0
(7450 3350);
DISPLAY 0.617021 (7450 3350);
PAINT BLUE (7450 3350);
FORCEPROP 1 LAST LOCATION R8E35
J 0
(7550 3475);
DISPLAY 0.617021 (7550 3475);
PAINT AQUA (7550 3475);
FORCEPROP 2 LAST CDS_LOCATION R8E35
J 0
(7550 3475);
DISPLAY 0.617021 (7550 3475);
PAINT AQUA (7550 3475);
DISPLAY INVISIBLE (7550 3475);
FORCEPROP 2 LAST ROOM P3V3_STBY_VR
J 0
(7600 3425);
PAINT GREEN (7600 3425);
DISPLAY INVISIBLE (7600 3425);
FORCEPROP 2 LAST CDS_LIB mstr_discrete
J 0
(7600 3425);
PAINT MONO (7600 3425);
DISPLAY INVISIBLE (7600 3425);
FORCEPROP 2 LAST BOM_COST P3V3_STBY_VR
J 0
(7600 3425);
PAINT WHITE (7600 3425);
DISPLAY INVISIBLE (7600 3425);
FORCEPROP 1 LAST PATH I127
J 0
(7550 3575);
DISPLAY 0.978723 (7550 3575);
PAINT WHITE (7550 3575);
DISPLAY INVISIBLE (7550 3575);
FORCEPROP 0 LAST SPOF TRUE
J 0
(7550 3575);
DISPLAY 1.021277 (7550 3575);
PAINT ORANGE (7550 3575);
DISPLAY INVISIBLE (7550 3575);
FORCEPROP 2 LAST REUSE_ID 13
J 0
(7550 3625);
DISPLAY 1.042553 (7550 3625);
PAINT ORANGE (7550 3625);
DISPLAY INVISIBLE (7550 3625);
FORCEPROP 2 LAST CDS_SEC 1
J 0
(7550 3625);
DISPLAY 1.042553 (7550 3625);
PAINT ORANGE (7550 3625);
DISPLAY INVISIBLE (7550 3625);
FORCEPROP 2 LAST $SEC 1
J 0
(7550 3625);
DISPLAY 0.680851 (7550 3625);
PAINT MONO (7550 3625);
DISPLAY INVISIBLE (7550 3625);
FORCEADD GND..1
(8150 4025);
FORCEPROP 3 LASTPIN (8150 4075) SIG_NAME GND\g
J 0
(8160 4085);
DISPLAY 0.659574 (8160 4085);
PAINT MONO (8160 4085);
DISPLAY INVISIBLE (8160 4085);
FORCEPROP 1 LAST VOLTAGE 0
J 0
(8150 4025);
PAINT SKYBLUE (8150 4025);
DISPLAY INVISIBLE (8150 4025);
FORCEPROP 2 LAST CDS_LIB mstr_symbols
J 0
(8150 4025);
PAINT MONO (8150 4025);
DISPLAY INVISIBLE (8150 4025);
FORCEPROP 1 LAST BODY_TYPE PLUMBING
J 0
(8105 3982);
DISPLAY 0.340426 (8105 3982);
PAINT GREEN (8105 3982);
DISPLAY INVISIBLE (8105 3982);
FORCEPROP 2 LAST BOM_COST PVPP_KLM_VR
J 0
(7300 4100);
DISPLAY 1.042553 (7300 4100);
PAINT WHITE (7300 4100);
DISPLAY INVISIBLE (7300 4100);
FORCEPROP 2 LAST ROOM PVPP_KLM_VR
J 0
(7575 4100);
DISPLAY 1.042553 (7575 4100);
PAINT GREEN (7575 4100);
DISPLAY INVISIBLE (7575 4100);
FORCEPROP 1 LAST HDL_POWER GND
J 0
(8150 4175);
DISPLAY 0.872340 (8150 4175);
PAINT GREEN (8150 4175);
DISPLAY INVISIBLE (8150 4175);
FORCEPROP 1 LAST PATH I128
J 0
(8225 4025);
DISPLAY 0.872340 (8225 4025);
PAINT AQUA (8225 4025);
DISPLAY INVISIBLE (8225 4025);
FORCEPROP 1 LAST SIZE 1B
J 0
(8225 3975);
DISPLAY 0.872340 (8225 3975);
PAINT GREEN (8225 3975);
DISPLAY INVISIBLE (8225 3975);
FORCEADD CAP..2
R 2
(8300 3425);
FORCEPROP 1 LASTPIN (8200 3425) $PN 2
J 2
(8215 3440);
DISPLAY 0.617021 (8215 3440);
PAINT WHITE (8215 3440);
FORCEPROP 1 LAST PART_NUMBER 602433-020
J 1
(8300 3475);
DISPLAY 0.617021 (8300 3475);
PAINT BLUE (8300 3475);
FORCEPROP 1 LAST MATERIAL X7R
J 2
(8300 3275);
DISPLAY 0.617021 (8300 3275);
PAINT SKYBLUE (8300 3275);
FORCEPROP 1 LAST PACK_TYPE 0603LF
J 1
(8300 3225);
DISPLAY 0.617021 (8300 3225);
PAINT SKYBLUE (8300 3225);
FORCEPROP 1 LAST TOLERANCE 10%
J 0
(8300 3275);
DISPLAY 0.617021 (8300 3275);
PAINT SKYBLUE (8300 3275);
FORCEPROP 1 LAST VOLTAGE 25V
J 2
(8300 3325);
DISPLAY 0.617021 (8300 3325);
PAINT SKYBLUE (8300 3325);
FORCEPROP 1 LAST VALUE 0.1UF
J 0
(8300 3325);
DISPLAY 0.617021 (8300 3325);
PAINT SKYBLUE (8300 3325);
FORCEPROP 1 LASTPIN (8400 3425) $PN 1
J 2
(8410 3440);
DISPLAY 0.617021 (8410 3440);
PAINT WHITE (8410 3440);
FORCEPROP 1 LAST LOCATION C8E12
J 1
(8300 3525);
DISPLAY 0.617021 (8300 3525);
PAINT AQUA (8300 3525);
FORCEPROP 2 LAST ROOM P3V3_STBY_VR
J 2
(8300 3550);
DISPLAY 0.765957 (8300 3550);
PAINT GREEN (8300 3550);
DISPLAY INVISIBLE (8300 3550);
FORCEPROP 2 LAST CDS_LOCATION C8E12
J 1
(8300 3525);
DISPLAY 0.617021 (8300 3525);
PAINT AQUA (8300 3525);
DISPLAY INVISIBLE (8300 3525);
FORCEPROP 2 LAST CDS_LIB mstr_discrete
J 0
(8300 3425);
PAINT MONO (8300 3425);
DISPLAY INVISIBLE (8300 3425);
FORCEPROP 2 LAST BOM_COST P3V3_STBY_VR
J 0
(8255 3585);
DISPLAY 1.042553 (8255 3585);
PAINT WHITE (8255 3585);
DISPLAY INVISIBLE (8255 3585);
FORCEPROP 2 LAST REUSE_ID 27
J 0
(8300 3675);
DISPLAY 1.042553 (8300 3675);
PAINT ORANGE (8300 3675);
DISPLAY INVISIBLE (8300 3675);
FORCEPROP 0 LAST SPOF TRUE
J 0
(8300 3625);
DISPLAY 1.021277 (8300 3625);
PAINT ORANGE (8300 3625);
DISPLAY INVISIBLE (8300 3625);
FORCEPROP 2 LAST CDS_SEC 1
J 0
(8255 3635);
DISPLAY 1.042553 (8255 3635);
PAINT ORANGE (8255 3635);
DISPLAY INVISIBLE (8255 3635);
FORCEPROP 2 LAST $SEC 1
J 0
(8300 3675);
DISPLAY 0.680851 (8300 3675);
PAINT MONO (8300 3675);
DISPLAY INVISIBLE (8300 3675);
FORCEPROP 1 LAST PATH I129
J 2
(8300 3625);
DISPLAY 0.978723 (8300 3625);
PAINT WHITE (8300 3625);
DISPLAY INVISIBLE (8300 3625);
FORCEADD P3V3_STBY..1
(6275 4150);
FORCEPROP 3 LASTPIN (6275 4100) SIG_NAME P3V3_STBY\g
J 0
(6285 4110);
DISPLAY 0.659574 (6285 4110);
PAINT MONO (6285 4110);
DISPLAY INVISIBLE (6285 4110);
FORCEPROP 1 LAST HDL_POWER P3V3_STBY
J 0
(5975 4025);
DISPLAY 0.872340 (5975 4025);
PAINT ORANGE (5975 4025);
DISPLAY INVISIBLE (5975 4025);
FORCEPROP 1 LAST PATH I130
J 0
(6320 4152);
DISPLAY 0.340426 (6320 4152);
PAINT GREEN (6320 4152);
DISPLAY INVISIBLE (6320 4152);
FORCEPROP 1 LAST BODY_TYPE PLUMBING
J 0
(6230 4107);
DISPLAY 0.340426 (6230 4107);
PAINT GREEN (6230 4107);
DISPLAY INVISIBLE (6230 4107);
FORCEPROP 2 LAST CDS_LIB mstr_symbols
J 0
(6275 4150);
PAINT MONO (6275 4150);
DISPLAY INVISIBLE (6275 4150);
FORCEPROP 1 LAST SIZE 1B
J 0
(6320 4172);
DISPLAY 0.340426 (6320 4172);
PAINT GREEN (6320 4172);
DISPLAY INVISIBLE (6320 4172);
FORCEPROP 1 LAST VOLTAGE +3.3V
J 0
(6475 4300);
DISPLAY 1.021277 (6475 4300);
PAINT SKYBLUE (6475 4300);
DISPLAY INVISIBLE (6475 4300);
FORCEADD P12V_STBY..1
(6750 4650);
FORCEPROP 3 LASTPIN (6750 4600) SIG_NAME P12V_STBY\g
J 0
(6760 4610);
DISPLAY 0.659574 (6760 4610);
PAINT MONO (6760 4610);
DISPLAY INVISIBLE (6760 4610);
FORCEPROP 1 LAST HDL_POWER P12V_STBY
J 0
(6450 4525);
DISPLAY 0.872340 (6450 4525);
PAINT ORANGE (6450 4525);
DISPLAY INVISIBLE (6450 4525);
FORCEPROP 1 LAST BODY_TYPE PLUMBING
J 0
(6705 4607);
DISPLAY 0.340426 (6705 4607);
PAINT GREEN (6705 4607);
DISPLAY INVISIBLE (6705 4607);
FORCEPROP 1 LAST VOLTAGE 12.0V
J 0
(6705 4607);
DISPLAY 0.340426 (6705 4607);
PAINT SKYBLUE (6705 4607);
DISPLAY INVISIBLE (6705 4607);
FORCEPROP 1 LAST PATH I131
J 0
(6795 4652);
DISPLAY 0.340426 (6795 4652);
PAINT GREEN (6795 4652);
DISPLAY INVISIBLE (6795 4652);
FORCEPROP 2 LAST CDS_LIB mstr_symbols
J 0
(6750 4650);
PAINT ORANGE (6750 4650);
DISPLAY INVISIBLE (6750 4650);
FORCEPROP 1 LAST SIZE 1B
J 0
(6795 4672);
DISPLAY 0.340426 (6795 4672);
PAINT GREEN (6795 4672);
DISPLAY INVISIBLE (6795 4672);
FORCEADD FERRITE..1
(6900 4500);
FORCEPROP 1 LASTPIN (6800 4500) $PN 1
J 2
(6835 4510);
DISPLAY 0.617021 (6835 4510);
PAINT WHITE (6835 4510);
FORCEPROP 1 LAST VALUE 22
J 2
(6880 4400);
DISPLAY 0.617021 (6880 4400);
PAINT SKYBLUE (6880 4400);
FORCEPROP 1 LAST MATERIAL FB
J 0
(6905 4400);
DISPLAY 0.617021 (6905 4400);
PAINT SKYBLUE (6905 4400);
FORCEPROP 1 LAST LOCATION FB9E1
J 0
(6805 4555);
DISPLAY 0.617021 (6805 4555);
PAINT AQUA (6805 4555);
FORCEPROP 1 LAST PACK_TYPE SM
J 0
(6980 4400);
DISPLAY 0.617021 (6980 4400);
PAINT SKYBLUE (6980 4400);
FORCEPROP 1 LASTPIN (7000 4500) $PN 2
J 0
(6980 4510);
DISPLAY 0.617021 (6980 4510);
PAINT WHITE (6980 4510);
FORCEPROP 1 LAST PART_NUMBER 656554-051
J 0
(6805 4615);
DISPLAY 0.617021 (6805 4615);
PAINT BLUE (6805 4615);
FORCEPROP 2 LAST CDS_LOCATION FB9E1
J 0
(6805 4555);
DISPLAY 0.617021 (6805 4555);
PAINT AQUA (6805 4555);
DISPLAY INVISIBLE (6805 4555);
FORCEPROP 2 LAST CDS_LIB mstr_discrete
J 0
(6900 4500);
PAINT MONO (6900 4500);
DISPLAY INVISIBLE (6900 4500);
FORCEPROP 2 LAST ROOM P3V3_STBY_VR
J 0
(6825 4650);
DISPLAY 1.659574 (6825 4650);
PAINT GREEN (6825 4650);
DISPLAY INVISIBLE (6825 4650);
FORCEPROP 1 LAST PATH I132
J 0
(6805 4665);
DISPLAY 0.872340 (6805 4665);
PAINT PURPLE (6805 4665);
DISPLAY INVISIBLE (6805 4665);
FORCEPROP 2 LAST SEC 1
J 0
(6825 4725);
DISPLAY 1.106383 (6825 4725);
PAINT MONO (6825 4725);
DISPLAY INVISIBLE (6825 4725);
FORCEPROP 2 LAST SEC_TYPE SM
J 0
(6825 4725);
DISPLAY 1.659574 (6825 4725);
PAINT ORANGE (6825 4725);
DISPLAY INVISIBLE (6825 4725);
FORCEPROP 0 LAST TOLERANCE 1%
J 0
(6825 4650);
PAINT SKYBLUE (6825 4650);
DISPLAY INVISIBLE (6825 4650);
FORCEADD GND..1
(7125 4175);
FORCEPROP 3 LASTPIN (7125 4225) SIG_NAME GND\g
J 0
(7135 4235);
DISPLAY 0.659574 (7135 4235);
PAINT MONO (7135 4235);
DISPLAY INVISIBLE (7135 4235);
FORCEPROP 2 LAST BOM_COST PVPP_KLM_VR
J 0
(6275 4250);
DISPLAY 1.042553 (6275 4250);
PAINT WHITE (6275 4250);
DISPLAY INVISIBLE (6275 4250);
FORCEPROP 2 LAST ROOM PVPP_KLM_VR
J 0
(6550 4250);
DISPLAY 1.042553 (6550 4250);
PAINT GREEN (6550 4250);
DISPLAY INVISIBLE (6550 4250);
FORCEPROP 1 LAST BODY_TYPE PLUMBING
J 0
(7080 4132);
DISPLAY 0.340426 (7080 4132);
PAINT GREEN (7080 4132);
DISPLAY INVISIBLE (7080 4132);
FORCEPROP 2 LAST CDS_LIB mstr_symbols
J 0
(7125 4175);
PAINT MONO (7125 4175);
DISPLAY INVISIBLE (7125 4175);
FORCEPROP 1 LAST VOLTAGE 0
J 0
(7125 4175);
PAINT SKYBLUE (7125 4175);
DISPLAY INVISIBLE (7125 4175);
FORCEPROP 1 LAST HDL_POWER GND
J 0
(7125 4325);
DISPLAY 0.872340 (7125 4325);
PAINT GREEN (7125 4325);
DISPLAY INVISIBLE (7125 4325);
FORCEPROP 1 LAST PATH I133
J 0
(7200 4175);
DISPLAY 0.872340 (7200 4175);
PAINT AQUA (7200 4175);
DISPLAY INVISIBLE (7200 4175);
FORCEPROP 1 LAST SIZE 1B
J 0
(7200 4125);
DISPLAY 0.872340 (7200 4125);
PAINT GREEN (7200 4125);
DISPLAY INVISIBLE (7200 4125);
FORCEADD CAP..1
(7125 4325);
FORCEPROP 1 LASTPIN (7125 4225) $PN 2
J 0
(7135 4205);
DISPLAY 0.617021 (7135 4205);
PAINT WHITE (7135 4205);
FORCEPROP 1 LASTPIN (7125 4425) $PN 1
J 0
(7135 4405);
DISPLAY 0.617021 (7135 4405);
PAINT WHITE (7135 4405);
FORCEPROP 1 LAST MATERIAL X6S
J 0
(7175 4225);
DISPLAY 0.617021 (7175 4225);
PAINT SKYBLUE (7175 4225);
FORCEPROP 1 LAST VOLTAGE 16V
J 0
(7175 4325);
DISPLAY 0.617021 (7175 4325);
PAINT SKYBLUE (7175 4325);
FORCEPROP 1 LAST PACK_TYPE 1210
J 0
(7175 4125);
DISPLAY 0.617021 (7175 4125);
PAINT SKYBLUE (7175 4125);
FORCEPROP 1 LAST TOLERANCE 20%
J 0
(7175 4275);
DISPLAY 0.617021 (7175 4275);
PAINT SKYBLUE (7175 4275);
FORCEPROP 1 LAST VALUE 47UF
J 0
(7175 4375);
DISPLAY 0.617021 (7175 4375);
PAINT SKYBLUE (7175 4375);
FORCEPROP 1 LAST LOCATION C9F1
J 0
(7175 4425);
DISPLAY 0.617021 (7175 4425);
PAINT AQUA (7175 4425);
FORCEPROP 1 LAST PART_NUMBER D38464-007
J 0
(7175 4175);
DISPLAY 0.617021 (7175 4175);
PAINT BLUE (7175 4175);
FORCEPROP 2 LAST ROOM P3V3_STBY_VR
J 0
(7125 4325);
PAINT GREEN (7125 4325);
DISPLAY INVISIBLE (7125 4325);
FORCEPROP 2 LAST CDS_LIB mstr_discrete
J 0
(7125 4325);
PAINT MONO (7125 4325);
DISPLAY INVISIBLE (7125 4325);
FORCEPROP 2 LAST BOM_COST P3V3_STBY_VR
J 0
(7125 4325);
PAINT WHITE (7125 4325);
DISPLAY INVISIBLE (7125 4325);
FORCEPROP 1 LAST PATH I134
J 0
(7175 4475);
DISPLAY 0.978723 (7175 4475);
PAINT WHITE (7175 4475);
DISPLAY INVISIBLE (7175 4475);
FORCEPROP 2 LAST CDS_LOCATION C9F1
J 0
(7175 4425);
DISPLAY 0.617021 (7175 4425);
PAINT AQUA (7175 4425);
DISPLAY INVISIBLE (7175 4425);
FORCEPROP 2 LAST $SEC 1
J 0
(7175 4525);
DISPLAY 0.680851 (7175 4525);
PAINT MONO (7175 4525);
DISPLAY INVISIBLE (7175 4525);
FORCEPROP 2 LAST CDS_SEC 1
J 0
(7175 4525);
DISPLAY 1.042553 (7175 4525);
PAINT ORANGE (7175 4525);
DISPLAY INVISIBLE (7175 4525);
FORCEADD CAP..1
(7475 4325);
FORCEPROP 1 LASTPIN (7475 4225) $PN 2
J 0
(7485 4205);
DISPLAY 0.617021 (7485 4205);
PAINT WHITE (7485 4205);
FORCEPROP 1 LAST MATERIAL X6S
J 0
(7525 4225);
DISPLAY 0.617021 (7525 4225);
PAINT SKYBLUE (7525 4225);
FORCEPROP 1 LAST VOLTAGE 16V
J 0
(7525 4325);
DISPLAY 0.617021 (7525 4325);
PAINT SKYBLUE (7525 4325);
FORCEPROP 1 LAST PACK_TYPE 1210
J 0
(7525 4125);
DISPLAY 0.617021 (7525 4125);
PAINT SKYBLUE (7525 4125);
FORCEPROP 1 LAST TOLERANCE 20%
J 0
(7525 4275);
DISPLAY 0.617021 (7525 4275);
PAINT SKYBLUE (7525 4275);
FORCEPROP 1 LASTPIN (7475 4425) $PN 1
J 0
(7485 4405);
DISPLAY 0.617021 (7485 4405);
PAINT WHITE (7485 4405);
FORCEPROP 1 LAST LOCATION C8E11
J 0
(7525 4425);
DISPLAY 0.617021 (7525 4425);
PAINT AQUA (7525 4425);
FORCEPROP 1 LAST VALUE 47UF
J 0
(7525 4375);
DISPLAY 0.617021 (7525 4375);
PAINT SKYBLUE (7525 4375);
FORCEPROP 1 LAST PART_NUMBER D38464-007
J 0
(7525 4175);
DISPLAY 0.617021 (7525 4175);
PAINT BLUE (7525 4175);
FORCEPROP 2 LAST ROOM P3V3_STBY_VR
J 0
(7475 4325);
PAINT GREEN (7475 4325);
DISPLAY INVISIBLE (7475 4325);
FORCEPROP 2 LAST CDS_LIB mstr_discrete
J 0
(7475 4325);
PAINT MONO (7475 4325);
DISPLAY INVISIBLE (7475 4325);
FORCEPROP 2 LAST BOM_COST P3V3_STBY_VR
J 0
(7475 4325);
PAINT WHITE (7475 4325);
DISPLAY INVISIBLE (7475 4325);
FORCEPROP 2 LAST CDS_SEC 1
J 0
(7525 4525);
DISPLAY 1.042553 (7525 4525);
PAINT ORANGE (7525 4525);
DISPLAY INVISIBLE (7525 4525);
FORCEPROP 2 LAST $SEC 1
J 0
(7525 4525);
DISPLAY 0.680851 (7525 4525);
PAINT MONO (7525 4525);
DISPLAY INVISIBLE (7525 4525);
FORCEPROP 2 LAST CDS_LOCATION C8E11
J 0
(7525 4425);
DISPLAY 0.617021 (7525 4425);
PAINT AQUA (7525 4425);
DISPLAY INVISIBLE (7525 4425);
FORCEPROP 1 LAST PATH I135
J 0
(7525 4475);
DISPLAY 0.978723 (7525 4475);
PAINT WHITE (7525 4475);
DISPLAY INVISIBLE (7525 4475);
FORCEADD GND..1
(7475 4175);
FORCEPROP 3 LASTPIN (7475 4225) SIG_NAME GND\g
J 0
(7485 4235);
DISPLAY 0.659574 (7485 4235);
PAINT MONO (7485 4235);
DISPLAY INVISIBLE (7485 4235);
FORCEPROP 2 LAST BOM_COST PVPP_KLM_VR
J 0
(6625 4250);
DISPLAY 1.042553 (6625 4250);
PAINT WHITE (6625 4250);
DISPLAY INVISIBLE (6625 4250);
FORCEPROP 2 LAST ROOM PVPP_KLM_VR
J 0
(6900 4250);
DISPLAY 1.042553 (6900 4250);
PAINT GREEN (6900 4250);
DISPLAY INVISIBLE (6900 4250);
FORCEPROP 1 LAST PATH I136
J 0
(7550 4175);
DISPLAY 0.872340 (7550 4175);
PAINT AQUA (7550 4175);
DISPLAY INVISIBLE (7550 4175);
FORCEPROP 1 LAST BODY_TYPE PLUMBING
J 0
(7430 4132);
DISPLAY 0.340426 (7430 4132);
PAINT GREEN (7430 4132);
DISPLAY INVISIBLE (7430 4132);
FORCEPROP 2 LAST CDS_LIB mstr_symbols
J 0
(7475 4175);
PAINT MONO (7475 4175);
DISPLAY INVISIBLE (7475 4175);
FORCEPROP 1 LAST SIZE 1B
J 0
(7550 4125);
DISPLAY 0.872340 (7550 4125);
PAINT GREEN (7550 4125);
DISPLAY INVISIBLE (7550 4125);
FORCEPROP 1 LAST VOLTAGE 0
J 0
(7475 4175);
PAINT SKYBLUE (7475 4175);
DISPLAY INVISIBLE (7475 4175);
FORCEPROP 1 LAST HDL_POWER GND
J 0
(7475 4325);
DISPLAY 0.872340 (7475 4325);
PAINT GREEN (7475 4325);
DISPLAY INVISIBLE (7475 4325);
FORCEADD CAP..1
(7825 4325);
FORCEPROP 1 LASTPIN (7825 4225) $PN 2
J 0
(7835 4205);
DISPLAY 0.617021 (7835 4205);
PAINT WHITE (7835 4205);
FORCEPROP 1 LASTPIN (7825 4425) $PN 1
J 0
(7835 4405);
DISPLAY 0.617021 (7835 4405);
PAINT WHITE (7835 4405);
FORCEPROP 1 LAST MATERIAL X6S
J 0
(7875 4225);
DISPLAY 0.617021 (7875 4225);
PAINT SKYBLUE (7875 4225);
FORCEPROP 1 LAST VOLTAGE 16V
J 0
(7875 4325);
DISPLAY 0.617021 (7875 4325);
PAINT SKYBLUE (7875 4325);
FORCEPROP 1 LAST PACK_TYPE 1206LF
J 0
(7875 4125);
DISPLAY 0.617021 (7875 4125);
PAINT SKYBLUE (7875 4125);
FORCEPROP 1 LAST TOLERANCE 10%
J 0
(7875 4275);
DISPLAY 0.617021 (7875 4275);
PAINT SKYBLUE (7875 4275);
FORCEPROP 1 LAST VALUE 22UF
J 0
(7875 4375);
DISPLAY 0.617021 (7875 4375);
PAINT SKYBLUE (7875 4375);
FORCEPROP 1 LAST PART_NUMBER D38464-005
J 0
(7875 4175);
DISPLAY 0.617021 (7875 4175);
PAINT BLUE (7875 4175);
FORCEPROP 1 LAST LOCATION C8E10
J 0
(7875 4425);
DISPLAY 0.617021 (7875 4425);
PAINT AQUA (7875 4425);
FORCEPROP 2 LAST ROOM P3V3_STBY_VR
J 0
(7825 4325);
PAINT GREEN (7825 4325);
DISPLAY INVISIBLE (7825 4325);
FORCEPROP 2 LAST CDS_LIB mstr_discrete
J 0
(7825 4325);
PAINT MONO (7825 4325);
DISPLAY INVISIBLE (7825 4325);
FORCEPROP 2 LAST BOM_COST P3V3_STBY_VR
J 0
(7825 4325);
PAINT WHITE (7825 4325);
DISPLAY INVISIBLE (7825 4325);
FORCEPROP 1 LAST PATH I137
J 0
(7875 4475);
DISPLAY 0.978723 (7875 4475);
PAINT WHITE (7875 4475);
DISPLAY INVISIBLE (7875 4475);
FORCEPROP 2 LAST CDS_LOCATION C8E10
J 0
(7875 4425);
DISPLAY 0.617021 (7875 4425);
PAINT AQUA (7875 4425);
DISPLAY INVISIBLE (7875 4425);
FORCEPROP 2 LAST $SEC 1
J 0
(7875 4525);
DISPLAY 0.680851 (7875 4525);
PAINT MONO (7875 4525);
DISPLAY INVISIBLE (7875 4525);
FORCEPROP 2 LAST CDS_SEC 1
J 0
(7875 4525);
DISPLAY 1.042553 (7875 4525);
PAINT ORANGE (7875 4525);
DISPLAY INVISIBLE (7875 4525);
FORCEADD GND..1
(7825 4175);
FORCEPROP 3 LASTPIN (7825 4225) SIG_NAME GND\g
J 0
(7835 4235);
DISPLAY 0.659574 (7835 4235);
PAINT MONO (7835 4235);
DISPLAY INVISIBLE (7835 4235);
FORCEPROP 2 LAST BOM_COST PVPP_KLM_VR
J 0
(6975 4250);
DISPLAY 1.042553 (6975 4250);
PAINT WHITE (6975 4250);
DISPLAY INVISIBLE (6975 4250);
FORCEPROP 2 LAST ROOM PVPP_KLM_VR
J 0
(7250 4250);
DISPLAY 1.042553 (7250 4250);
PAINT GREEN (7250 4250);
DISPLAY INVISIBLE (7250 4250);
FORCEPROP 1 LAST BODY_TYPE PLUMBING
J 0
(7780 4132);
DISPLAY 0.340426 (7780 4132);
PAINT GREEN (7780 4132);
DISPLAY INVISIBLE (7780 4132);
FORCEPROP 2 LAST CDS_LIB mstr_symbols
J 0
(7825 4175);
PAINT MONO (7825 4175);
DISPLAY INVISIBLE (7825 4175);
FORCEPROP 1 LAST VOLTAGE 0
J 0
(7825 4175);
PAINT SKYBLUE (7825 4175);
DISPLAY INVISIBLE (7825 4175);
FORCEPROP 1 LAST SIZE 1B
J 0
(7900 4125);
DISPLAY 0.872340 (7900 4125);
PAINT GREEN (7900 4125);
DISPLAY INVISIBLE (7900 4125);
FORCEPROP 1 LAST PATH I138
J 0
(7900 4175);
DISPLAY 0.872340 (7900 4175);
PAINT AQUA (7900 4175);
DISPLAY INVISIBLE (7900 4175);
FORCEPROP 1 LAST HDL_POWER GND
J 0
(7825 4325);
DISPLAY 0.872340 (7825 4325);
PAINT GREEN (7825 4325);
DISPLAY INVISIBLE (7825 4325);
FORCEADD CAP..1
(8150 4350);
FORCEPROP 1 LASTPIN (8150 4250) $PN 2
J 0
(8160 4230);
DISPLAY 0.617021 (8160 4230);
PAINT WHITE (8160 4230);
FORCEPROP 1 LASTPIN (8150 4450) $PN 1
J 0
(8160 4430);
DISPLAY 0.617021 (8160 4430);
PAINT WHITE (8160 4430);
FORCEPROP 1 LAST MATERIAL X6S
J 0
(8200 4250);
DISPLAY 0.617021 (8200 4250);
PAINT SKYBLUE (8200 4250);
FORCEPROP 1 LAST VOLTAGE 16V
J 0
(8200 4350);
DISPLAY 0.617021 (8200 4350);
PAINT SKYBLUE (8200 4350);
FORCEPROP 1 LAST PACK_TYPE 0402
J 0
(8200 4150);
DISPLAY 0.617021 (8200 4150);
PAINT SKYBLUE (8200 4150);
FORCEPROP 1 LAST TOLERANCE 10%
J 0
(8200 4300);
DISPLAY 0.617021 (8200 4300);
PAINT SKYBLUE (8200 4300);
FORCEPROP 1 LAST VALUE 1.0UF
J 0
(8200 4400);
DISPLAY 0.617021 (8200 4400);
PAINT SKYBLUE (8200 4400);
FORCEPROP 1 LAST PART_NUMBER D97712-011
J 0
(8200 4200);
DISPLAY 0.617021 (8200 4200);
PAINT BLUE (8200 4200);
FORCEPROP 1 LAST LOCATION C8E14
J 0
(8200 4450);
DISPLAY 0.617021 (8200 4450);
PAINT AQUA (8200 4450);
FORCEPROP 2 LAST CDS_LIB mstr_discrete
J 0
(8150 4350);
PAINT MONO (8150 4350);
DISPLAY INVISIBLE (8150 4350);
FORCEPROP 2 LAST BOM_COST P3V3_STBY_VR
J 0
(8150 4350);
PAINT WHITE (8150 4350);
DISPLAY INVISIBLE (8150 4350);
FORCEPROP 2 LAST ROOM P3V3_STBY_VR
J 0
(8150 4350);
PAINT GREEN (8150 4350);
DISPLAY INVISIBLE (8150 4350);
FORCEPROP 1 LAST PATH I139
J 0
(8200 4500);
DISPLAY 0.978723 (8200 4500);
PAINT WHITE (8200 4500);
DISPLAY INVISIBLE (8200 4500);
FORCEPROP 2 LAST CDS_LOCATION C8E14
J 0
(8200 4450);
DISPLAY 0.617021 (8200 4450);
PAINT AQUA (8200 4450);
DISPLAY INVISIBLE (8200 4450);
FORCEPROP 2 LAST $SEC 1
J 0
(8200 4550);
DISPLAY 0.680851 (8200 4550);
PAINT MONO (8200 4550);
DISPLAY INVISIBLE (8200 4550);
FORCEPROP 2 LAST CDS_SEC 1
J 0
(8200 4550);
DISPLAY 1.042553 (8200 4550);
PAINT ORANGE (8200 4550);
DISPLAY INVISIBLE (8200 4550);
FORCEPROP 0 LAST FIN VR_1P2
J 0
(8200 4650);
PAINT ORANGE (8200 4650);
DISPLAY INVISIBLE (8200 4650);
FORCEPROP 0 LAST REUSE_ID 1
J 0
(8200 4550);
DISPLAY 1.042553 (8200 4550);
PAINT ORANGE (8200 4550);
DISPLAY INVISIBLE (8200 4550);
FORCEADD RES..1
(9225 925);
FORCEPROP 1 LASTPIN (9125 925) $PN 1
J 0
(9137 937);
DISPLAY 0.617021 (9137 937);
PAINT GREEN (9137 937);
FORCEPROP 1 LAST VALUE 0.0
J 2
(9200 850);
DISPLAY 0.617021 (9200 850);
PAINT SKYBLUE (9200 850);
FORCEPROP 1 LAST WATTAGE 1/16W
J 2
(9275 800);
DISPLAY 0.617021 (9275 800);
PAINT SKYBLUE (9275 800);
FORCEPROP 1 LAST PACK_TYPE 0402
J 0
(9175 775);
DISPLAY 0.617021 (9175 775);
PAINT SKYBLUE (9175 775);
FORCEPROP 1 LAST LOCATION R8E38
J 0
(9175 975);
DISPLAY 0.617021 (9175 975);
PAINT AQUA (9175 975);
FORCEPROP 1 LASTPIN (9325 925) $PN 2
J 0
(9287 937);
DISPLAY 0.617021 (9287 937);
PAINT GREEN (9287 937);
FORCEPROP 1 LAST TOLERANCE 5%
J 0
(9225 850);
DISPLAY 0.617021 (9225 850);
PAINT SKYBLUE (9225 850);
FORCEPROP 1 LAST PART_NUMBER G21497-005
J 0
(9225 1025);
DISPLAY 0.617021 (9225 1025);
PAINT BLUE (9225 1025);
FORCEPROP 2 LAST CDS_LOCATION R8E38
J 0
(9175 975);
DISPLAY 0.617021 (9175 975);
PAINT AQUA (9175 975);
DISPLAY INVISIBLE (9175 975);
FORCEPROP 2 LAST CDS_SEC 1
J 0
(9175 1125);
PAINT MONO (9175 1125);
DISPLAY INVISIBLE (9175 1125);
FORCEPROP 2 LAST $SEC 1
J 0
(9175 1125);
PAINT MONO (9175 1125);
DISPLAY INVISIBLE (9175 1125);
FORCEPROP 1 LAST PATH I140
J 0
(9175 1075);
DISPLAY 0.978723 (9175 1075);
PAINT WHITE (9175 1075);
DISPLAY INVISIBLE (9175 1075);
FORCEPROP 2 LAST ROOM P3V3_STBY_VR
J 0
(9175 1025);
PAINT ORANGE (9175 1025);
DISPLAY INVISIBLE (9175 1025);
FORCEPROP 2 LAST CDS_LIB mstr_discrete
J 0
(9225 925);
PAINT ORANGE (9225 925);
DISPLAY INVISIBLE (9225 925);
FORCEPROP 1 LAST MATERIAL CHIP
J 0
(9225 775);
PAINT SKYBLUE (9225 775);
DISPLAY INVISIBLE (9225 775);
FORCEPROP 2 LAST BOM_COST P3V3_STBY_VR
J 0
(9300 1075);
PAINT MONO (9300 1075);
DISPLAY INVISIBLE (9300 1075);
FORCEADD RES..2
(9475 1100);
FORCEPROP 1 LAST PACK_TYPE 0402
J 0
(9515 925);
DISPLAY 0.617021 (9515 925);
PAINT SKYBLUE (9515 925);
FORCEPROP 1 LAST PART_NUMBER G21796-016
J 0
(9515 975);
DISPLAY 0.617021 (9515 975);
PAINT BLUE (9515 975);
FORCEPROP 1 LASTPIN (9475 1000) $PN 2
J 0
(9480 1010);
DISPLAY 0.617021 (9480 1010);
PAINT WHITE (9480 1010);
FORCEPROP 1 LAST TOLERANCE 1%
J 0
(9520 1125);
DISPLAY 0.617021 (9520 1125);
PAINT SKYBLUE (9520 1125);
FORCEPROP 1 LASTPIN (9475 1200) $PN 1
J 0
(9480 1162);
DISPLAY 0.617021 (9480 1162);
PAINT WHITE (9480 1162);
FORCEPROP 1 LAST LOCATION R8E34
J 0
(9520 1225);
DISPLAY 0.617021 (9520 1225);
PAINT AQUA (9520 1225);
FORCEPROP 1 LAST VALUE 10.0K
J 0
(9520 1175);
DISPLAY 0.617021 (9520 1175);
PAINT SKYBLUE (9520 1175);
FORCEPROP 1 LAST MATERIAL CHIP
J 0
(9515 1025);
DISPLAY 0.617021 (9515 1025);
PAINT SKYBLUE (9515 1025);
FORCEPROP 1 LAST WATTAGE 1/16W
J 0
(9515 1075);
DISPLAY 0.617021 (9515 1075);
PAINT SKYBLUE (9515 1075);
FORCEPROP 2 LAST BOM_COST P3V3_STBY_VR
R 1
J 0
(9175 1150);
DISPLAY 1.042553 (9175 1150);
PAINT WHITE (9175 1150);
DISPLAY INVISIBLE (9175 1150);
FORCEPROP 2 LAST ROOM P3V3_STBY_VR
R 1
J 0
(9275 1150);
DISPLAY 1.042553 (9275 1150);
PAINT GREEN (9275 1150);
DISPLAY INVISIBLE (9275 1150);
FORCEPROP 2 LAST CDS_LIB mstr_discrete
R 1
J 0
(9475 1100);
PAINT MONO (9475 1100);
DISPLAY INVISIBLE (9475 1100);
FORCEPROP 2 LAST CDS_LOCATION R8E34
J 0
(9520 1225);
DISPLAY 0.617021 (9520 1225);
PAINT AQUA (9520 1225);
DISPLAY INVISIBLE (9520 1225);
FORCEPROP 1 LAST PATH I142
J 0
(9525 1275);
DISPLAY 0.978723 (9525 1275);
PAINT WHITE (9525 1275);
DISPLAY INVISIBLE (9525 1275);
FORCEPROP 2 LAST $SEC 1
J 0
(9525 1325);
DISPLAY 0.680851 (9525 1325);
PAINT MONO (9525 1325);
DISPLAY INVISIBLE (9525 1325);
FORCEPROP 0 LAST SPOF TRUE
J 0
(9525 1325);
DISPLAY 1.021277 (9525 1325);
PAINT ORANGE (9525 1325);
DISPLAY INVISIBLE (9525 1325);
FORCEPROP 2 LAST REUSE_ID 7
J 0
(9525 1325);
DISPLAY 1.042553 (9525 1325);
PAINT ORANGE (9525 1325);
DISPLAY INVISIBLE (9525 1325);
FORCEPROP 2 LAST CDS_SEC 1
J 0
(9525 1325);
DISPLAY 1.042553 (9525 1325);
PAINT ORANGE (9525 1325);
DISPLAY INVISIBLE (9525 1325);
FORCEADD RES..2
(9475 1425);
FORCEPROP 1 LASTPIN (9475 1525) $PN 1
J 0
(9480 1487);
DISPLAY 0.617021 (9480 1487);
PAINT WHITE (9480 1487);
FORCEPROP 1 LASTPIN (9475 1325) $PN 2
J 0
(9480 1335);
DISPLAY 0.617021 (9480 1335);
PAINT WHITE (9480 1335);
FORCEPROP 1 LAST TOLERANCE 1%
J 0
(9520 1450);
DISPLAY 0.617021 (9520 1450);
PAINT SKYBLUE (9520 1450);
FORCEPROP 1 LAST VALUE 23.2K
J 0
(9520 1500);
DISPLAY 0.617021 (9520 1500);
PAINT SKYBLUE (9520 1500);
FORCEPROP 1 LAST PACK_TYPE 0402
J 0
(9515 1375);
DISPLAY 0.617021 (9515 1375);
PAINT SKYBLUE (9515 1375);
FORCEPROP 1 LAST WATTAGE 1/16W
J 0
(9515 1400);
DISPLAY 0.617021 (9515 1400);
PAINT SKYBLUE (9515 1400);
FORCEPROP 1 LAST MATERIAL CHIP
J 0
(9515 1350);
DISPLAY 0.617021 (9515 1350);
PAINT SKYBLUE (9515 1350);
FORCEPROP 1 LAST LOCATION R8E31
J 0
(9520 1550);
DISPLAY 0.617021 (9520 1550);
PAINT AQUA (9520 1550);
FORCEPROP 1 LAST PART_NUMBER G21796-114
J 0
(9515 1325);
DISPLAY 0.617021 (9515 1325);
PAINT BLUE (9515 1325);
FORCEPROP 2 LAST CDS_LIB mstr_discrete
J 0
(9475 1425);
PAINT MONO (9475 1425);
DISPLAY INVISIBLE (9475 1425);
FORCEPROP 2 LAST ROOM P3V3_STBY_VR
J 0
(9520 1580);
PAINT GREEN (9520 1580);
DISPLAY INVISIBLE (9520 1580);
FORCEPROP 1 LAST PATH I143
J 0
(9525 1600);
DISPLAY 0.978723 (9525 1600);
PAINT WHITE (9525 1600);
DISPLAY INVISIBLE (9525 1600);
FORCEPROP 2 LAST CDS_LOCATION R8E31
J 0
(9520 1550);
DISPLAY 0.617021 (9520 1550);
PAINT AQUA (9520 1550);
DISPLAY INVISIBLE (9520 1550);
FORCEPROP 2 LAST $SEC 1
J 0
(9525 1650);
DISPLAY 0.680851 (9525 1650);
PAINT MONO (9525 1650);
DISPLAY INVISIBLE (9525 1650);
FORCEPROP 2 LAST CDS_SEC 1
J 0
(9525 1650);
DISPLAY 1.042553 (9525 1650);
PAINT ORANGE (9525 1650);
DISPLAY INVISIBLE (9525 1650);
FORCEPROP 2 LAST REUSE_ID 9
J 0
(9525 1650);
DISPLAY 1.042553 (9525 1650);
PAINT ORANGE (9525 1650);
DISPLAY INVISIBLE (9525 1650);
FORCEPROP 2 LAST BOM_COST P3V3_STBY_VR
J 0
(9520 1605);
DISPLAY 1.042553 (9520 1605);
PAINT WHITE (9520 1605);
DISPLAY INVISIBLE (9520 1605);
FORCEPROP 0 LAST SPOF TRUE
J 0
(9525 1650);
DISPLAY 1.021277 (9525 1650);
PAINT ORANGE (9525 1650);
DISPLAY INVISIBLE (9525 1650);
FORCEADD RES..1
R 5
(9475 1825);
FORCEPROP 1 LASTPIN (9475 1725) $PN 2
J 0
(9487 1763);
DISPLAY 0.617021 (9487 1763);
PAINT ORANGE (9487 1763);
FORCEPROP 1 LAST PACK_TYPE 0402
J 0
(9500 1675);
DISPLAY 0.617021 (9500 1675);
PAINT SKYBLUE (9500 1675);
FORCEPROP 1 LAST MATERIAL CHIP
J 0
(9500 1725);
DISPLAY 0.617021 (9500 1725);
PAINT SKYBLUE (9500 1725);
FORCEPROP 1 LAST TOLERANCE 5%
J 0
(9500 1775);
DISPLAY 0.617021 (9500 1775);
PAINT SKYBLUE (9500 1775);
FORCEPROP 1 LAST LOCATION R8E25
J 0
(9575 1775);
DISPLAY 0.617021 (9575 1775);
PAINT AQUA (9575 1775);
FORCEPROP 1 LAST VALUE 0.0
J 0
(9500 1850);
DISPLAY 0.617021 (9500 1850);
PAINT SKYBLUE (9500 1850);
FORCEPROP 1 LASTPIN (9475 1925) $PN 1
J 0
(9487 1913);
DISPLAY 0.617021 (9487 1913);
PAINT ORANGE (9487 1913);
FORCEPROP 1 LAST WATTAGE 1/16W
J 0
(9500 1825);
DISPLAY 0.617021 (9500 1825);
PAINT SKYBLUE (9500 1825);
FORCEPROP 1 LAST PART_NUMBER G21497-005
J 0
(9500 1625);
DISPLAY 0.617021 (9500 1625);
PAINT BLUE (9500 1625);
FORCEPROP 2 LAST CDS_LOCATION R8E25
J 0
(9575 1775);
DISPLAY 0.617021 (9575 1775);
PAINT AQUA (9575 1775);
DISPLAY INVISIBLE (9575 1775);
FORCEPROP 2 LAST SEC 1
J 0
(9550 1975);
DISPLAY 0.680851 (9550 1975);
PAINT MONO (9550 1975);
DISPLAY INVISIBLE (9550 1975);
FORCEPROP 0 LAST SPOF TRUE
J 0
(9500 1950);
DISPLAY 1.021277 (9500 1950);
PAINT ORANGE (9500 1950);
DISPLAY INVISIBLE (9500 1950);
FORCEPROP 2 LAST SEC_TYPE 0402
J 0
(9550 1975);
DISPLAY 1.021277 (9550 1975);
PAINT ORANGE (9550 1975);
DISPLAY INVISIBLE (9550 1975);
FORCEPROP 2 LAST CDS_LIB mstr_discrete
J 0
(9475 1825);
PAINT ORANGE (9475 1825);
DISPLAY INVISIBLE (9475 1825);
FORCEPROP 1 LAST PATH I144
R 3
J 0
(9625 1875);
DISPLAY 0.978723 (9625 1875);
PAINT WHITE (9625 1875);
DISPLAY INVISIBLE (9625 1875);
FORCEPROP 2 LAST ROOM PVPP_KLM_VR
R 3
J 0
(9625 1875);
DISPLAY 1.659574 (9625 1875);
PAINT GREEN (9625 1875);
DISPLAY INVISIBLE (9625 1875);
FORCEADD GND..1
(10175 1625);
FORCEPROP 3 LASTPIN (10175 1675) SIG_NAME GND\g
J 0
(10185 1685);
DISPLAY 0.659574 (10185 1685);
PAINT MONO (10185 1685);
DISPLAY INVISIBLE (10185 1685);
FORCEPROP 2 LAST BOM_COST PVPP_KLM_VR
J 0
(9325 1700);
DISPLAY 1.042553 (9325 1700);
PAINT WHITE (9325 1700);
DISPLAY INVISIBLE (9325 1700);
FORCEPROP 2 LAST ROOM PVPP_KLM_VR
J 0
(9600 1700);
DISPLAY 1.042553 (9600 1700);
PAINT GREEN (9600 1700);
DISPLAY INVISIBLE (9600 1700);
FORCEPROP 1 LAST HDL_POWER GND
J 0
(10175 1775);
DISPLAY 0.872340 (10175 1775);
PAINT GREEN (10175 1775);
DISPLAY INVISIBLE (10175 1775);
FORCEPROP 1 LAST BODY_TYPE PLUMBING
J 0
(10130 1582);
DISPLAY 0.340426 (10130 1582);
PAINT GREEN (10130 1582);
DISPLAY INVISIBLE (10130 1582);
FORCEPROP 2 LAST CDS_LIB mstr_symbols
J 0
(10175 1625);
PAINT MONO (10175 1625);
DISPLAY INVISIBLE (10175 1625);
FORCEPROP 1 LAST VOLTAGE 0
J 0
(10175 1625);
PAINT SKYBLUE (10175 1625);
DISPLAY INVISIBLE (10175 1625);
FORCEPROP 1 LAST PATH I145
J 0
(10250 1625);
DISPLAY 0.872340 (10250 1625);
PAINT AQUA (10250 1625);
DISPLAY INVISIBLE (10250 1625);
FORCEPROP 1 LAST SIZE 1B
J 0
(10250 1575);
DISPLAY 0.872340 (10250 1575);
PAINT AQUA (10250 1575);
DISPLAY INVISIBLE (10250 1575);
FORCEADD RES..1
(10475 1725);
FORCEPROP 1 LAST PACK_TYPE 0402
J 0
(10400 1525);
DISPLAY 0.617021 (10400 1525);
PAINT SKYBLUE (10400 1525);
FORCEPROP 1 LAST VALUE 0.0
J 2
(10450 1625);
DISPLAY 0.617021 (10450 1625);
PAINT SKYBLUE (10450 1625);
FORCEPROP 1 LAST WATTAGE 1/16W
J 2
(10475 1575);
DISPLAY 0.617021 (10475 1575);
PAINT SKYBLUE (10475 1575);
FORCEPROP 1 LASTPIN (10375 1725) $PN 1
J 0
(10387 1737);
DISPLAY 0.617021 (10387 1737);
PAINT WHITE (10387 1737);
FORCEPROP 1 LAST MATERIAL CHIP
J 0
(10475 1575);
DISPLAY 0.617021 (10475 1575);
PAINT SKYBLUE (10475 1575);
FORCEPROP 1 LAST TOLERANCE 5%
J 0
(10475 1625);
DISPLAY 0.617021 (10475 1625);
PAINT SKYBLUE (10475 1625);
FORCEPROP 1 LAST PART_NUMBER G21497-005
J 0
(10350 1675);
DISPLAY 0.617021 (10350 1675);
PAINT BLUE (10350 1675);
FORCEPROP 1 LAST LOCATION R8F11
J 0
(10425 1775);
DISPLAY 0.617021 (10425 1775);
PAINT AQUA (10425 1775);
FORCEPROP 1 LASTPIN (10575 1725) $PN 2
J 0
(10537 1737);
DISPLAY 0.617021 (10537 1737);
PAINT WHITE (10537 1737);
FORCEPROP 2 LAST CDS_LIB mstr_discrete
J 0
(10475 1725);
PAINT MONO (10475 1725);
DISPLAY INVISIBLE (10475 1725);
FORCEPROP 2 LAST CDS_LOCATION R8F11
J 0
(10425 1775);
DISPLAY 0.617021 (10425 1775);
PAINT AQUA (10425 1775);
DISPLAY INVISIBLE (10425 1775);
FORCEPROP 2 LAST CDS_SEC 1
J 0
(10435 1910);
PAINT MONO (10435 1910);
DISPLAY INVISIBLE (10435 1910);
FORCEPROP 2 LAST $SEC 1
J 0
(10440 1930);
PAINT MONO (10440 1930);
DISPLAY INVISIBLE (10440 1930);
FORCEPROP 1 LAST PATH I146
J 0
(10425 1875);
DISPLAY 0.978723 (10425 1875);
PAINT WHITE (10425 1875);
DISPLAY INVISIBLE (10425 1875);
FORCEPROP 2 LAST ROOM P3V3_STBY_VR
J 0
(10425 1800);
PAINT GREEN (10425 1800);
DISPLAY INVISIBLE (10425 1800);
FORCEADD GND..1
(9875 3075);
FORCEPROP 3 LASTPIN (9875 3125) SIG_NAME GND\g
J 0
(9885 3135);
DISPLAY 0.659574 (9885 3135);
PAINT MONO (9885 3135);
DISPLAY INVISIBLE (9885 3135);
FORCEPROP 2 LAST BOM_COST PVPP_KLM_VR
J 0
(9025 3150);
DISPLAY 1.042553 (9025 3150);
PAINT WHITE (9025 3150);
DISPLAY INVISIBLE (9025 3150);
FORCEPROP 1 LAST BODY_TYPE PLUMBING
J 0
(9830 3032);
DISPLAY 0.340426 (9830 3032);
PAINT GREEN (9830 3032);
DISPLAY INVISIBLE (9830 3032);
FORCEPROP 1 LAST SIZE 1B
J 0
(9950 3025);
DISPLAY 0.872340 (9950 3025);
PAINT AQUA (9950 3025);
DISPLAY INVISIBLE (9950 3025);
FORCEPROP 2 LAST ROOM PVPP_KLM_VR
J 0
(9300 3150);
DISPLAY 1.042553 (9300 3150);
PAINT GREEN (9300 3150);
DISPLAY INVISIBLE (9300 3150);
FORCEPROP 1 LAST HDL_POWER GND
J 0
(9875 3225);
DISPLAY 0.872340 (9875 3225);
PAINT GREEN (9875 3225);
DISPLAY INVISIBLE (9875 3225);
FORCEPROP 1 LAST VOLTAGE 0
J 0
(9875 3075);
PAINT SKYBLUE (9875 3075);
DISPLAY INVISIBLE (9875 3075);
FORCEPROP 2 LAST CDS_LIB mstr_symbols
J 0
(9875 3075);
PAINT MONO (9875 3075);
DISPLAY INVISIBLE (9875 3075);
FORCEPROP 1 LAST PATH I147
J 0
(9950 3075);
DISPLAY 0.872340 (9950 3075);
PAINT AQUA (9950 3075);
DISPLAY INVISIBLE (9950 3075);
FORCEADD RES..2
(10450 3550);
FORCEPROP 1 LASTPIN (10450 3450) $PN 2
J 0
(10455 3460);
DISPLAY 0.617021 (10455 3460);
PAINT WHITE (10455 3460);
FORCEPROP 1 LAST WATTAGE 1/16W
J 0
(10565 3475);
DISPLAY 0.617021 (10565 3475);
PAINT SKYBLUE (10565 3475);
FORCEPROP 1 LAST PACK_TYPE 0402
J 0
(10565 3425);
DISPLAY 0.617021 (10565 3425);
PAINT SKYBLUE (10565 3425);
FORCEPROP 1 LAST MATERIAL EMPTY
J 0
(10565 3525);
DISPLAY 0.617021 (10565 3525);
PAINT RED (10565 3525);
FORCEPROP 1 LAST TOLERANCE 5%
J 0
(10570 3575);
DISPLAY 0.617021 (10570 3575);
PAINT SKYBLUE (10570 3575);
FORCEPROP 1 LASTPIN (10450 3650) $PN 1
J 0
(10455 3612);
DISPLAY 0.617021 (10455 3612);
PAINT WHITE (10455 3612);
FORCEPROP 1 LAST LOCATION R8F3
J 0
(10495 3650);
DISPLAY 0.617021 (10495 3650);
PAINT AQUA (10495 3650);
FORCEPROP 1 LAST VALUE 2.2
J 0
(10570 3625);
DISPLAY 0.617021 (10570 3625);
PAINT SKYBLUE (10570 3625);
FORCEPROP 1 LAST PART_NUMBER G21497-016
J 0
(10565 3375);
DISPLAY 0.617021 (10565 3375);
PAINT BLUE (10565 3375);
FORCEPROP 2 LAST CDS_LIB mstr_discrete
J 0
(10450 3550);
PAINT MONO (10450 3550);
DISPLAY INVISIBLE (10450 3550);
FORCEPROP 2 LAST CDS_LOCATION R8F3
J 0
(10495 3650);
DISPLAY 0.617021 (10495 3650);
PAINT AQUA (10495 3650);
DISPLAY INVISIBLE (10495 3650);
FORCEPROP 2 LAST ROOM P3V3_STBY_VR
J 0
(10500 3700);
PAINT GREEN (10500 3700);
DISPLAY INVISIBLE (10500 3700);
FORCEPROP 1 LAST PATH I148
J 0
(10500 3725);
DISPLAY 0.978723 (10500 3725);
PAINT WHITE (10500 3725);
DISPLAY INVISIBLE (10500 3725);
FORCEPROP 2 LAST $SEC 1
J 0
(10500 3775);
DISPLAY 0.680851 (10500 3775);
PAINT MONO (10500 3775);
DISPLAY INVISIBLE (10500 3775);
FORCEPROP 2 LAST CDS_SEC 1
J 0
(10500 3775);
DISPLAY 1.042553 (10500 3775);
PAINT ORANGE (10500 3775);
DISPLAY INVISIBLE (10500 3775);
FORCEPROP 2 LAST REUSE_ID 29
J 0
(10500 3775);
DISPLAY 1.042553 (10500 3775);
PAINT ORANGE (10500 3775);
DISPLAY INVISIBLE (10500 3775);
FORCEPROP 2 LAST BOM_COST P3V3_STBY_VR
J 0
(10500 3725);
DISPLAY 1.042553 (10500 3725);
PAINT WHITE (10500 3725);
DISPLAY INVISIBLE (10500 3725);
FORCEADD GND..1
(10450 3350);
FORCEPROP 3 LASTPIN (10450 3400) SIG_NAME GND\g
J 0
(10460 3410);
DISPLAY 0.659574 (10460 3410);
PAINT MONO (10460 3410);
DISPLAY INVISIBLE (10460 3410);
FORCEPROP 2 LAST BOM_COST PVPP_KLM_VR
J 0
(9550 3500);
DISPLAY 1.042553 (9550 3500);
PAINT WHITE (9550 3500);
DISPLAY INVISIBLE (9550 3500);
FORCEPROP 2 LAST ROOM PVPP_KLM_VR
J 0
(9800 3500);
PAINT GREEN (9800 3500);
DISPLAY INVISIBLE (9800 3500);
FORCEPROP 1 LAST BODY_TYPE PLUMBING
J 0
(10405 3307);
DISPLAY 0.340426 (10405 3307);
PAINT GREEN (10405 3307);
DISPLAY INVISIBLE (10405 3307);
FORCEPROP 2 LAST CDS_LIB mstr_symbols
J 0
(10450 3425);
PAINT MONO (10450 3425);
DISPLAY INVISIBLE (10450 3425);
FORCEPROP 1 LAST VOLTAGE 0
J 0
(10450 3425);
PAINT SKYBLUE (10450 3425);
DISPLAY INVISIBLE (10450 3425);
FORCEPROP 1 LAST PATH I149
J 0
(10525 3350);
DISPLAY 0.872340 (10525 3350);
PAINT AQUA (10525 3350);
DISPLAY INVISIBLE (10525 3350);
FORCEPROP 1 LAST SIZE 1B
J 0
(10525 3375);
DISPLAY 0.893617 (10525 3375);
PAINT GREEN (10525 3375);
DISPLAY INVISIBLE (10525 3375);
FORCEPROP 1 LAST HDL_POWER GND
J 0
(10450 3575);
DISPLAY 0.893617 (10450 3575);
PAINT GREEN (10450 3575);
DISPLAY INVISIBLE (10450 3575);
FORCEADD GND..1
(11025 3625);
FORCEPROP 3 LASTPIN (11025 3675) SIG_NAME GND\g
J 0
(11035 3685);
DISPLAY 0.659574 (11035 3685);
PAINT MONO (11035 3685);
DISPLAY INVISIBLE (11035 3685);
FORCEPROP 2 LAST BOM_COST PVPP_KLM_VR
J 0
(10175 3700);
DISPLAY 1.042553 (10175 3700);
PAINT WHITE (10175 3700);
DISPLAY INVISIBLE (10175 3700);
FORCEPROP 2 LAST ROOM PVPP_KLM_VR
J 0
(10450 3700);
DISPLAY 1.042553 (10450 3700);
PAINT GREEN (10450 3700);
DISPLAY INVISIBLE (10450 3700);
FORCEPROP 1 LAST BODY_TYPE PLUMBING
J 0
(10980 3582);
DISPLAY 0.340426 (10980 3582);
PAINT GREEN (10980 3582);
DISPLAY INVISIBLE (10980 3582);
FORCEPROP 1 LAST SIZE 1B
J 0
(11100 3575);
DISPLAY 0.872340 (11100 3575);
PAINT GREEN (11100 3575);
DISPLAY INVISIBLE (11100 3575);
FORCEPROP 1 LAST VOLTAGE 0
J 0
(11025 3625);
PAINT SKYBLUE (11025 3625);
DISPLAY INVISIBLE (11025 3625);
FORCEPROP 1 LAST PATH I151
J 0
(11100 3625);
DISPLAY 0.872340 (11100 3625);
PAINT AQUA (11100 3625);
DISPLAY INVISIBLE (11100 3625);
FORCEPROP 2 LAST CDS_LIB mstr_symbols
J 0
(11025 3625);
PAINT MONO (11025 3625);
DISPLAY INVISIBLE (11025 3625);
FORCEPROP 1 LAST HDL_POWER GND
J 0
(11025 3775);
DISPLAY 0.872340 (11025 3775);
PAINT GREEN (11025 3775);
DISPLAY INVISIBLE (11025 3775);
FORCEADD RES..2
(11025 3875);
FORCEPROP 1 LASTPIN (11025 3775) $PN 2
J 0
(11030 3785);
DISPLAY 0.617021 (11030 3785);
PAINT WHITE (11030 3785);
FORCEPROP 1 LAST PACK_TYPE 0402
J 0
(11065 3675);
DISPLAY 0.617021 (11065 3675);
PAINT SKYBLUE (11065 3675);
FORCEPROP 1 LAST MATERIAL CHIP
J 0
(11065 3775);
DISPLAY 0.617021 (11065 3775);
PAINT SKYBLUE (11065 3775);
FORCEPROP 1 LAST WATTAGE 1/16W
J 0
(11065 3825);
DISPLAY 0.617021 (11065 3825);
PAINT SKYBLUE (11065 3825);
FORCEPROP 1 LASTPIN (11025 3975) $PN 1
J 0
(11030 3937);
DISPLAY 0.617021 (11030 3937);
PAINT WHITE (11030 3937);
FORCEPROP 1 LAST LOCATION R2T4
J 0
(11070 4000);
DISPLAY 0.617021 (11070 4000);
PAINT AQUA (11070 4000);
FORCEPROP 1 LAST VALUE 1.0K
J 0
(11070 3925);
DISPLAY 0.617021 (11070 3925);
PAINT SKYBLUE (11070 3925);
FORCEPROP 1 LAST TOLERANCE 0.1%
J 0
(11070 3875);
DISPLAY 0.617021 (11070 3875);
PAINT SKYBLUE (11070 3875);
FORCEPROP 1 LAST PART_NUMBER G85996-004
J 0
(11065 3725);
DISPLAY 0.617021 (11065 3725);
PAINT BLUE (11065 3725);
FORCEPROP 2 LAST CDS_LIB mstr_discrete
J 0
(11025 3875);
PAINT MONO (11025 3875);
DISPLAY INVISIBLE (11025 3875);
FORCEPROP 2 LAST ROOM P3V3_STBY_VR
J 0
(11070 4030);
PAINT GREEN (11070 4030);
DISPLAY INVISIBLE (11070 4030);
FORCEPROP 1 LAST PATH I152
J 0
(11075 4050);
DISPLAY 0.978723 (11075 4050);
PAINT WHITE (11075 4050);
DISPLAY INVISIBLE (11075 4050);
FORCEPROP 2 LAST CDS_LOCATION R2T4
J 0
(11070 4000);
DISPLAY 0.617021 (11070 4000);
PAINT AQUA (11070 4000);
DISPLAY INVISIBLE (11070 4000);
FORCEPROP 2 LAST BOM_COST P3V3_STBY_VR
J 0
(11070 4055);
DISPLAY 1.042553 (11070 4055);
PAINT WHITE (11070 4055);
DISPLAY INVISIBLE (11070 4055);
FORCEPROP 2 LAST $SEC 1
J 0
(11075 4100);
DISPLAY 0.680851 (11075 4100);
PAINT MONO (11075 4100);
DISPLAY INVISIBLE (11075 4100);
FORCEPROP 2 LAST CDS_SEC 1
J 0
(11075 4100);
DISPLAY 1.042553 (11075 4100);
PAINT ORANGE (11075 4100);
DISPLAY INVISIBLE (11075 4100);
FORCEPROP 2 LAST REUSE_ID 34
J 0
(11075 4100);
DISPLAY 1.042553 (11075 4100);
PAINT ORANGE (11075 4100);
DISPLAY INVISIBLE (11075 4100);
FORCEADD GND..1
(11350 3650);
FORCEPROP 3 LASTPIN (11350 3700) SIG_NAME GND\g
J 0
(11360 3710);
DISPLAY 0.659574 (11360 3710);
PAINT MONO (11360 3710);
DISPLAY INVISIBLE (11360 3710);
FORCEPROP 2 LAST BOM_COST PVPP_KLM_VR
J 0
(10500 3725);
DISPLAY 1.042553 (10500 3725);
PAINT WHITE (10500 3725);
DISPLAY INVISIBLE (10500 3725);
FORCEPROP 2 LAST ROOM PVPP_KLM_VR
J 0
(10775 3725);
DISPLAY 1.042553 (10775 3725);
PAINT GREEN (10775 3725);
DISPLAY INVISIBLE (10775 3725);
FORCEPROP 1 LAST VOLTAGE 0
J 0
(11350 3650);
PAINT SKYBLUE (11350 3650);
DISPLAY INVISIBLE (11350 3650);
FORCEPROP 2 LAST CDS_LIB mstr_symbols
J 0
(11350 3650);
PAINT MONO (11350 3650);
DISPLAY INVISIBLE (11350 3650);
FORCEPROP 1 LAST BODY_TYPE PLUMBING
J 0
(11305 3607);
DISPLAY 0.340426 (11305 3607);
PAINT GREEN (11305 3607);
DISPLAY INVISIBLE (11305 3607);
FORCEPROP 1 LAST HDL_POWER GND
J 0
(11350 3800);
DISPLAY 0.872340 (11350 3800);
PAINT GREEN (11350 3800);
DISPLAY INVISIBLE (11350 3800);
FORCEPROP 1 LAST SIZE 1B
J 0
(11425 3600);
DISPLAY 0.872340 (11425 3600);
PAINT GREEN (11425 3600);
DISPLAY INVISIBLE (11425 3600);
FORCEPROP 1 LAST PATH I153
J 0
(11425 3650);
DISPLAY 0.872340 (11425 3650);
PAINT AQUA (11425 3650);
DISPLAY INVISIBLE (11425 3650);
FORCEADD CAPP..1
(11350 3875);
FORCEPROP 1 LASTPIN (11350 3775) $PN 2
J 0
(11360 3760);
DISPLAY 0.617021 (11360 3760);
PAINT WHITE (11360 3760);
FORCEPROP 1 LAST PACK_TYPE 3018
J 0
(11400 3725);
DISPLAY 0.617021 (11400 3725);
PAINT SKYBLUE (11400 3725);
FORCEPROP 1 LAST VOLTAGE 6.3V
J 0
(11400 3825);
DISPLAY 0.617021 (11400 3825);
PAINT SKYBLUE (11400 3825);
FORCEPROP 1 LASTPIN (11350 3975) $PN 1
J 0
(11360 3960);
DISPLAY 0.617021 (11360 3960);
PAINT WHITE (11360 3960);
FORCEPROP 1 LAST TOLERANCE 20%
J 0
(11400 3875);
DISPLAY 0.617021 (11400 3875);
PAINT SKYBLUE (11400 3875);
FORCEPROP 1 LAST MATERIAL POSCAP
J 0
(11400 3775);
DISPLAY 0.617021 (11400 3775);
PAINT SKYBLUE (11400 3775);
FORCEPROP 1 LAST VALUE 470UF
J 0
(11400 3925);
DISPLAY 0.617021 (11400 3925);
PAINT SKYBLUE (11400 3925);
FORCEPROP 1 LAST PART_NUMBER 724613-091
J 0
(11400 3675);
DISPLAY 0.617021 (11400 3675);
PAINT BLUE (11400 3675);
FORCEPROP 1 LAST LOCATION C8F14
J 0
(11400 3975);
DISPLAY 0.617021 (11400 3975);
PAINT AQUA (11400 3975);
FORCEPROP 2 LAST ROOM P3V3_STBY_VR
J 0
(11350 3875);
PAINT GREEN (11350 3875);
DISPLAY INVISIBLE (11350 3875);
FORCEPROP 2 LAST CDS_LIB mstr_discrete
J 0
(11350 3875);
PAINT MONO (11350 3875);
DISPLAY INVISIBLE (11350 3875);
FORCEPROP 2 LAST BOM_COST P3V3_STBY_VR
J 0
(11350 3875);
DISPLAY 0.659574 (11350 3875);
PAINT WHITE (11350 3875);
DISPLAY INVISIBLE (11350 3875);
FORCEPROP 1 LAST PATH I154
J 0
(11400 4025);
DISPLAY 0.978723 (11400 4025);
PAINT ORANGE (11400 4025);
DISPLAY INVISIBLE (11400 4025);
FORCEPROP 2 LAST CDS_LOCATION C8F14
J 0
(11400 3975);
DISPLAY 0.617021 (11400 3975);
PAINT AQUA (11400 3975);
DISPLAY INVISIBLE (11400 3975);
FORCEPROP 2 LAST $SEC 1
J 0
(11400 4075);
DISPLAY 0.680851 (11400 4075);
PAINT MONO (11400 4075);
DISPLAY INVISIBLE (11400 4075);
FORCEPROP 2 LAST CDS_SEC 1
J 0
(11400 4075);
DISPLAY 1.042553 (11400 4075);
PAINT ORANGE (11400 4075);
DISPLAY INVISIBLE (11400 4075);
FORCEPROP 2 LAST REUSE_ID 28
J 0
(11400 4075);
DISPLAY 1.042553 (11400 4075);
PAINT ORANGE (11400 4075);
DISPLAY INVISIBLE (11400 4075);
FORCEADD CAPP..1
(11675 3875);
FORCEPROP 1 LASTPIN (11675 3775) $PN 2
J 0
(11685 3760);
DISPLAY 0.617021 (11685 3760);
PAINT WHITE (11685 3760);
FORCEPROP 1 LASTPIN (11675 3975) $PN 1
J 0
(11685 3960);
DISPLAY 0.617021 (11685 3960);
PAINT WHITE (11685 3960);
FORCEPROP 1 LAST MATERIAL POSCAP
J 0
(11725 3775);
DISPLAY 0.617021 (11725 3775);
PAINT SKYBLUE (11725 3775);
FORCEPROP 1 LAST VOLTAGE 6.3V
J 0
(11725 3825);
DISPLAY 0.617021 (11725 3825);
PAINT SKYBLUE (11725 3825);
FORCEPROP 1 LAST PACK_TYPE 3018
J 0
(11725 3725);
DISPLAY 0.617021 (11725 3725);
PAINT SKYBLUE (11725 3725);
FORCEPROP 1 LAST TOLERANCE 20%
J 0
(11725 3875);
DISPLAY 0.617021 (11725 3875);
PAINT SKYBLUE (11725 3875);
FORCEPROP 1 LAST VALUE 470UF
J 0
(11725 3925);
DISPLAY 0.617021 (11725 3925);
PAINT SKYBLUE (11725 3925);
FORCEPROP 1 LAST PART_NUMBER 724613-091
J 0
(11700 3700);
DISPLAY 0.617021 (11700 3700);
PAINT BLUE (11700 3700);
FORCEPROP 1 LAST LOCATION C8F8
J 0
(11725 3975);
DISPLAY 0.617021 (11725 3975);
PAINT AQUA (11725 3975);
FORCEPROP 2 LAST ROOM P3V3_STBY_VR
J 0
(11675 3875);
PAINT GREEN (11675 3875);
DISPLAY INVISIBLE (11675 3875);
FORCEPROP 2 LAST CDS_LIB mstr_discrete
J 0
(11675 3875);
PAINT MONO (11675 3875);
DISPLAY INVISIBLE (11675 3875);
FORCEPROP 2 LAST BOM_COST P3V3_STBY_VR
J 0
(11675 3875);
PAINT WHITE (11675 3875);
DISPLAY INVISIBLE (11675 3875);
FORCEPROP 1 LAST PATH I155
J 0
(11725 4025);
DISPLAY 0.978723 (11725 4025);
PAINT ORANGE (11725 4025);
DISPLAY INVISIBLE (11725 4025);
FORCEPROP 2 LAST CDS_LOCATION C8F8
J 0
(11725 3975);
DISPLAY 0.617021 (11725 3975);
PAINT AQUA (11725 3975);
DISPLAY INVISIBLE (11725 3975);
FORCEPROP 2 LAST $SEC 1
J 0
(11725 4075);
DISPLAY 0.680851 (11725 4075);
PAINT MONO (11725 4075);
DISPLAY INVISIBLE (11725 4075);
FORCEPROP 2 LAST CDS_SEC 1
J 0
(11725 4075);
DISPLAY 1.042553 (11725 4075);
PAINT ORANGE (11725 4075);
DISPLAY INVISIBLE (11725 4075);
FORCEPROP 2 LAST REUSE_ID 28
J 0
(11725 4075);
DISPLAY 1.042553 (11725 4075);
PAINT ORANGE (11725 4075);
DISPLAY INVISIBLE (11725 4075);
FORCEADD GND..1
(11675 3650);
FORCEPROP 3 LASTPIN (11675 3700) SIG_NAME GND\g
J 0
(11685 3710);
DISPLAY 0.659574 (11685 3710);
PAINT MONO (11685 3710);
DISPLAY INVISIBLE (11685 3710);
FORCEPROP 2 LAST BOM_COST PVPP_KLM_VR
J 0
(10825 3725);
DISPLAY 1.042553 (10825 3725);
PAINT WHITE (10825 3725);
DISPLAY INVISIBLE (10825 3725);
FORCEPROP 2 LAST ROOM PVPP_KLM_VR
J 0
(11100 3725);
DISPLAY 1.042553 (11100 3725);
PAINT GREEN (11100 3725);
DISPLAY INVISIBLE (11100 3725);
FORCEPROP 1 LAST BODY_TYPE PLUMBING
J 0
(11630 3607);
DISPLAY 0.340426 (11630 3607);
PAINT GREEN (11630 3607);
DISPLAY INVISIBLE (11630 3607);
FORCEPROP 1 LAST PATH I156
J 0
(11750 3650);
DISPLAY 0.872340 (11750 3650);
PAINT AQUA (11750 3650);
DISPLAY INVISIBLE (11750 3650);
FORCEPROP 2 LAST CDS_LIB mstr_symbols
J 0
(11675 3650);
PAINT MONO (11675 3650);
DISPLAY INVISIBLE (11675 3650);
FORCEPROP 1 LAST SIZE 1B
J 0
(11750 3600);
DISPLAY 0.872340 (11750 3600);
PAINT GREEN (11750 3600);
DISPLAY INVISIBLE (11750 3600);
FORCEPROP 1 LAST VOLTAGE 0
J 0
(11675 3650);
PAINT SKYBLUE (11675 3650);
DISPLAY INVISIBLE (11675 3650);
FORCEPROP 1 LAST HDL_POWER GND
J 0
(11675 3800);
DISPLAY 0.872340 (11675 3800);
PAINT GREEN (11675 3800);
DISPLAY INVISIBLE (11675 3800);
FORCEADD GND..1
(11950 3600);
FORCEPROP 3 LASTPIN (11950 3650) SIG_NAME GND\g
J 0
(11960 3660);
DISPLAY 0.659574 (11960 3660);
PAINT MONO (11960 3660);
DISPLAY INVISIBLE (11960 3660);
FORCEPROP 2 LAST BOM_COST PVPP_KLM_VR
J 0
(11100 3675);
DISPLAY 1.042553 (11100 3675);
PAINT WHITE (11100 3675);
DISPLAY INVISIBLE (11100 3675);
FORCEPROP 2 LAST ROOM PVPP_KLM_VR
J 0
(11375 3675);
DISPLAY 1.042553 (11375 3675);
PAINT GREEN (11375 3675);
DISPLAY INVISIBLE (11375 3675);
FORCEPROP 1 LAST BODY_TYPE PLUMBING
J 0
(11905 3557);
DISPLAY 0.340426 (11905 3557);
PAINT GREEN (11905 3557);
DISPLAY INVISIBLE (11905 3557);
FORCEPROP 1 LAST SIZE 1B
J 0
(12025 3550);
DISPLAY 0.872340 (12025 3550);
PAINT GREEN (12025 3550);
DISPLAY INVISIBLE (12025 3550);
FORCEPROP 1 LAST PATH I157
J 0
(12025 3600);
DISPLAY 0.872340 (12025 3600);
PAINT AQUA (12025 3600);
DISPLAY INVISIBLE (12025 3600);
FORCEPROP 2 LAST CDS_LIB mstr_symbols
J 0
(11950 3600);
PAINT MONO (11950 3600);
DISPLAY INVISIBLE (11950 3600);
FORCEPROP 1 LAST VOLTAGE 0
J 0
(11950 3600);
PAINT SKYBLUE (11950 3600);
DISPLAY INVISIBLE (11950 3600);
FORCEPROP 1 LAST HDL_POWER GND
J 0
(11950 3750);
DISPLAY 0.872340 (11950 3750);
PAINT GREEN (11950 3750);
DISPLAY INVISIBLE (11950 3750);
FORCEADD CAP..1
(11950 3875);
FORCEPROP 1 LASTPIN (11950 3775) $PN 2
J 0
(11960 3755);
DISPLAY 0.617021 (11960 3755);
PAINT WHITE (11960 3755);
FORCEPROP 1 LASTPIN (11950 3975) $PN 1
J 0
(11960 3955);
DISPLAY 0.617021 (11960 3955);
PAINT WHITE (11960 3955);
FORCEPROP 1 LAST MATERIAL X6S
J 0
(12000 3775);
DISPLAY 0.617021 (12000 3775);
PAINT SKYBLUE (12000 3775);
FORCEPROP 1 LAST VOLTAGE 6.3V
J 0
(12000 3875);
DISPLAY 0.617021 (12000 3875);
PAINT SKYBLUE (12000 3875);
FORCEPROP 1 LAST PACK_TYPE 0805
J 0
(12000 3675);
DISPLAY 0.617021 (12000 3675);
PAINT SKYBLUE (12000 3675);
FORCEPROP 1 LAST TOLERANCE 20%
J 0
(12000 3825);
DISPLAY 0.617021 (12000 3825);
PAINT SKYBLUE (12000 3825);
FORCEPROP 1 LAST VALUE 22UF
J 0
(12000 3925);
DISPLAY 0.617021 (12000 3925);
PAINT SKYBLUE (12000 3925);
FORCEPROP 1 LAST LOCATION C2T7
J 0
(12000 3975);
DISPLAY 0.617021 (12000 3975);
PAINT AQUA (12000 3975);
FORCEPROP 1 LAST PART_NUMBER C95333-008
J 0
(12000 3725);
DISPLAY 0.617021 (12000 3725);
PAINT BLUE (12000 3725);
FORCEPROP 2 LAST ROOM P3V3_STBY_VR
J 0
(11950 3875);
PAINT GREEN (11950 3875);
DISPLAY INVISIBLE (11950 3875);
FORCEPROP 2 LAST BOM_COST P3V3_STBY_VR
J 0
(11950 3875);
PAINT WHITE (11950 3875);
DISPLAY INVISIBLE (11950 3875);
FORCEPROP 2 LAST CDS_LIB mstr_discrete
J 0
(11950 3875);
PAINT MONO (11950 3875);
DISPLAY INVISIBLE (11950 3875);
FORCEPROP 1 LAST PATH I158
J 0
(12000 4025);
DISPLAY 0.978723 (12000 4025);
PAINT WHITE (12000 4025);
DISPLAY INVISIBLE (12000 4025);
FORCEPROP 2 LAST CDS_LOCATION C2T7
J 0
(12000 3975);
DISPLAY 0.617021 (12000 3975);
PAINT AQUA (12000 3975);
DISPLAY INVISIBLE (12000 3975);
FORCEPROP 2 LAST $SEC 1
J 0
(12000 4075);
DISPLAY 0.680851 (12000 4075);
PAINT MONO (12000 4075);
DISPLAY INVISIBLE (12000 4075);
FORCEPROP 2 LAST CDS_SEC 1
J 0
(12000 4075);
DISPLAY 1.042553 (12000 4075);
PAINT ORANGE (12000 4075);
DISPLAY INVISIBLE (12000 4075);
FORCEPROP 2 LAST REUSE_ID 33
J 0
(12000 4075);
DISPLAY 1.042553 (12000 4075);
PAINT ORANGE (12000 4075);
DISPLAY INVISIBLE (12000 4075);
FORCEADD GND..1
(12175 3600);
FORCEPROP 3 LASTPIN (12175 3650) SIG_NAME GND\g
J 0
(12185 3660);
DISPLAY 0.659574 (12185 3660);
PAINT MONO (12185 3660);
DISPLAY INVISIBLE (12185 3660);
FORCEPROP 2 LAST BOM_COST PVPP_KLM_VR
J 0
(11325 3675);
DISPLAY 1.042553 (11325 3675);
PAINT WHITE (11325 3675);
DISPLAY INVISIBLE (11325 3675);
FORCEPROP 2 LAST ROOM PVPP_KLM_VR
J 0
(11600 3675);
DISPLAY 1.042553 (11600 3675);
PAINT GREEN (11600 3675);
DISPLAY INVISIBLE (11600 3675);
FORCEPROP 1 LAST BODY_TYPE PLUMBING
J 0
(12130 3557);
DISPLAY 0.340426 (12130 3557);
PAINT GREEN (12130 3557);
DISPLAY INVISIBLE (12130 3557);
FORCEPROP 1 LAST SIZE 1B
J 0
(12250 3550);
DISPLAY 0.872340 (12250 3550);
PAINT GREEN (12250 3550);
DISPLAY INVISIBLE (12250 3550);
FORCEPROP 1 LAST VOLTAGE 0
J 0
(12175 3600);
PAINT SKYBLUE (12175 3600);
DISPLAY INVISIBLE (12175 3600);
FORCEPROP 2 LAST CDS_LIB mstr_symbols
J 0
(12175 3600);
PAINT MONO (12175 3600);
DISPLAY INVISIBLE (12175 3600);
FORCEPROP 1 LAST PATH I159
J 0
(12250 3600);
DISPLAY 0.872340 (12250 3600);
PAINT AQUA (12250 3600);
DISPLAY INVISIBLE (12250 3600);
FORCEPROP 1 LAST HDL_POWER GND
J 0
(12175 3750);
DISPLAY 0.872340 (12175 3750);
PAINT GREEN (12175 3750);
DISPLAY INVISIBLE (12175 3750);
FORCEADD CAP..1
(12175 3850);
FORCEPROP 1 LASTPIN (12175 3750) $PN 2
J 0
(12185 3730);
DISPLAY 0.617021 (12185 3730);
PAINT WHITE (12185 3730);
FORCEPROP 1 LASTPIN (12175 3950) $PN 1
J 0
(12185 3930);
DISPLAY 0.617021 (12185 3930);
PAINT WHITE (12185 3930);
FORCEPROP 1 LAST MATERIAL X6S
J 0
(12225 3750);
DISPLAY 0.617021 (12225 3750);
PAINT SKYBLUE (12225 3750);
FORCEPROP 1 LAST VOLTAGE 6.3V
J 0
(12225 3850);
DISPLAY 0.617021 (12225 3850);
PAINT SKYBLUE (12225 3850);
FORCEPROP 1 LAST PACK_TYPE 0805
J 0
(12225 3650);
DISPLAY 0.617021 (12225 3650);
PAINT SKYBLUE (12225 3650);
FORCEPROP 1 LAST TOLERANCE 20%
J 0
(12225 3800);
DISPLAY 0.617021 (12225 3800);
PAINT SKYBLUE (12225 3800);
FORCEPROP 1 LAST VALUE 22UF
J 0
(12225 3900);
DISPLAY 0.617021 (12225 3900);
PAINT SKYBLUE (12225 3900);
FORCEPROP 1 LAST PART_NUMBER C95333-008
J 0
(12225 3700);
DISPLAY 0.617021 (12225 3700);
PAINT BLUE (12225 3700);
FORCEPROP 1 LAST LOCATION C2T6
J 0
(12225 3950);
DISPLAY 0.617021 (12225 3950);
PAINT AQUA (12225 3950);
FORCEPROP 2 LAST ROOM P3V3_STBY_VR
J 0
(12175 3850);
PAINT GREEN (12175 3850);
DISPLAY INVISIBLE (12175 3850);
FORCEPROP 2 LAST CDS_LIB mstr_discrete
J 0
(12175 3850);
PAINT MONO (12175 3850);
DISPLAY INVISIBLE (12175 3850);
FORCEPROP 2 LAST BOM_COST P3V3_STBY_VR
J 0
(12175 3850);
PAINT WHITE (12175 3850);
DISPLAY INVISIBLE (12175 3850);
FORCEPROP 2 LAST CDS_LOCATION C2T6
J 0
(12225 3950);
DISPLAY 0.617021 (12225 3950);
PAINT AQUA (12225 3950);
DISPLAY INVISIBLE (12225 3950);
FORCEPROP 1 LAST PATH I160
J 0
(12225 4000);
DISPLAY 0.978723 (12225 4000);
PAINT WHITE (12225 4000);
DISPLAY INVISIBLE (12225 4000);
FORCEPROP 2 LAST $SEC 1
J 0
(12225 4050);
DISPLAY 0.680851 (12225 4050);
PAINT MONO (12225 4050);
DISPLAY INVISIBLE (12225 4050);
FORCEPROP 2 LAST REUSE_ID 33
J 0
(12225 4050);
DISPLAY 1.042553 (12225 4050);
PAINT ORANGE (12225 4050);
DISPLAY INVISIBLE (12225 4050);
FORCEPROP 2 LAST CDS_SEC 1
J 0
(12225 4050);
DISPLAY 1.042553 (12225 4050);
PAINT ORANGE (12225 4050);
DISPLAY INVISIBLE (12225 4050);
FORCEADD CAP..1
(10450 3900);
FORCEPROP 1 LASTPIN (10450 3800) $PN 2
J 0
(10460 3780);
DISPLAY 0.617021 (10460 3780);
PAINT WHITE (10460 3780);
FORCEPROP 1 LASTPIN (10450 4000) $PN 1
J 0
(10460 3980);
DISPLAY 0.617021 (10460 3980);
PAINT WHITE (10460 3980);
FORCEPROP 1 LAST PACK_TYPE 0402LF
J 0
(10575 3800);
DISPLAY 0.617021 (10575 3800);
PAINT SKYBLUE (10575 3800);
FORCEPROP 1 LAST VOLTAGE 50V
J 0
(10575 3900);
DISPLAY 0.617021 (10575 3900);
PAINT SKYBLUE (10575 3900);
FORCEPROP 1 LAST TOLERANCE 10%
J 0
(10575 3850);
DISPLAY 0.617021 (10575 3850);
PAINT SKYBLUE (10575 3850);
FORCEPROP 1 LAST VALUE 3300PF
J 0
(10575 3950);
DISPLAY 0.617021 (10575 3950);
PAINT SKYBLUE (10575 3950);
FORCEPROP 1 LAST LOCATION C8F3
J 0
(10550 4000);
DISPLAY 0.617021 (10550 4000);
PAINT AQUA (10550 4000);
FORCEPROP 1 LAST PART_NUMBER A36096-091
J 0
(10575 3750);
DISPLAY 0.617021 (10575 3750);
PAINT BLUE (10575 3750);
FORCEPROP 1 LAST MATERIAL EMPTY
J 0
(10675 3875);
DISPLAY 0.617021 (10675 3875);
PAINT RED (10675 3875);
FORCEPROP 2 LAST CDS_LIB mstr_discrete
J 0
(10450 3900);
PAINT MONO (10450 3900);
DISPLAY INVISIBLE (10450 3900);
FORCEPROP 2 LAST ROOM P3V3_STBY_VR
J 0
(10500 4025);
PAINT GREEN (10500 4025);
DISPLAY INVISIBLE (10500 4025);
FORCEPROP 1 LAST PATH I163
J 0
(10500 4050);
DISPLAY 0.978723 (10500 4050);
PAINT WHITE (10500 4050);
DISPLAY INVISIBLE (10500 4050);
FORCEPROP 2 LAST CDS_LOCATION C8F3
J 0
(10550 4000);
DISPLAY 0.617021 (10550 4000);
PAINT AQUA (10550 4000);
DISPLAY INVISIBLE (10550 4000);
FORCEPROP 2 LAST BOM_COST P3V3_STBY_VR
J 0
(10500 4050);
DISPLAY 1.042553 (10500 4050);
PAINT WHITE (10500 4050);
DISPLAY INVISIBLE (10500 4050);
FORCEPROP 2 LAST $SEC 1
J 0
(10500 4100);
DISPLAY 0.680851 (10500 4100);
PAINT MONO (10500 4100);
DISPLAY INVISIBLE (10500 4100);
FORCEPROP 2 LAST CDS_SEC 1
J 0
(10500 4100);
DISPLAY 1.042553 (10500 4100);
PAINT ORANGE (10500 4100);
DISPLAY INVISIBLE (10500 4100);
FORCEPROP 2 LAST REUSE_ID 26
J 0
(10500 4100);
DISPLAY 1.042553 (10500 4100);
PAINT ORANGE (10500 4100);
DISPLAY INVISIBLE (10500 4100);
FORCEADD AGND_SCSI..1
(6975 2100);
FORCEPROP 3 LASTPIN (6975 2150) SIG_NAME AGND_P3V3_STBY\g
J 0
(6985 2160);
DISPLAY 0.659574 (6985 2160);
PAINT MONO (6985 2160);
DISPLAY INVISIBLE (6985 2160);
FORCEPROP 1 LAST HDL_POWER AGND_P3V3_STBY
J 1
(7000 2025);
DISPLAY 0.617021 (7000 2025);
PAINT GREEN (7000 2025);
FORCEPROP 1 LAST VOLTAGE 0V
J 0
(6825 2125);
DISPLAY 1.021277 (6825 2125);
PAINT SKYBLUE (6825 2125);
DISPLAY INVISIBLE (6825 2125);
FORCEPROP 1 LAST PATH I164
J 0
(7050 2100);
DISPLAY 0.872340 (7050 2100);
PAINT AQUA (7050 2100);
DISPLAY INVISIBLE (7050 2100);
FORCEPROP 1 LAST BODY_TYPE PLUMBING
J 0
(6930 2057);
DISPLAY 0.340426 (6930 2057);
PAINT GREEN (6930 2057);
DISPLAY INVISIBLE (6930 2057);
FORCEPROP 2 LAST CDS_LIB mstr_symbols
J 0
(6975 2100);
PAINT MONO (6975 2100);
DISPLAY INVISIBLE (6975 2100);
FORCEADD AGND_SCSI..1
(6425 1550);
FORCEPROP 3 LASTPIN (6425 1600) SIG_NAME AGND_P3V3_STBY\g
J 0
(6435 1610);
DISPLAY 0.659574 (6435 1610);
PAINT MONO (6435 1610);
DISPLAY INVISIBLE (6435 1610);
FORCEPROP 1 LAST HDL_POWER AGND_P3V3_STBY
J 1
(6450 1475);
DISPLAY 0.617021 (6450 1475);
PAINT GREEN (6450 1475);
FORCEPROP 1 LAST BODY_TYPE PLUMBING
J 0
(6380 1507);
DISPLAY 0.340426 (6380 1507);
PAINT GREEN (6380 1507);
DISPLAY INVISIBLE (6380 1507);
FORCEPROP 1 LAST VOLTAGE 0V
J 0
(6275 1575);
DISPLAY 1.021277 (6275 1575);
PAINT SKYBLUE (6275 1575);
DISPLAY INVISIBLE (6275 1575);
FORCEPROP 1 LAST PATH I165
J 0
(6500 1550);
DISPLAY 0.872340 (6500 1550);
PAINT AQUA (6500 1550);
DISPLAY INVISIBLE (6500 1550);
FORCEPROP 2 LAST CDS_LIB mstr_symbols
J 0
(6425 1550);
PAINT MONO (6425 1550);
DISPLAY INVISIBLE (6425 1550);
FORCEADD AGND_SCSI..1
(6175 2175);
FORCEPROP 3 LASTPIN (6175 2225) SIG_NAME AGND_P3V3_STBY\g
J 0
(6185 2235);
DISPLAY 0.659574 (6185 2235);
PAINT MONO (6185 2235);
DISPLAY INVISIBLE (6185 2235);
FORCEPROP 1 LAST HDL_POWER AGND_P3V3_STBY
J 1
(6200 2100);
DISPLAY 0.617021 (6200 2100);
PAINT GREEN (6200 2100);
FORCEPROP 1 LAST BODY_TYPE PLUMBING
J 0
(6130 2132);
DISPLAY 0.340426 (6130 2132);
PAINT GREEN (6130 2132);
DISPLAY INVISIBLE (6130 2132);
FORCEPROP 1 LAST VOLTAGE 0V
J 0
(6025 2200);
DISPLAY 1.021277 (6025 2200);
PAINT SKYBLUE (6025 2200);
DISPLAY INVISIBLE (6025 2200);
FORCEPROP 1 LAST PATH I166
J 0
(6250 2175);
DISPLAY 0.872340 (6250 2175);
PAINT AQUA (6250 2175);
DISPLAY INVISIBLE (6250 2175);
FORCEPROP 2 LAST CDS_LIB mstr_symbols
J 0
(6175 2175);
PAINT MONO (6175 2175);
DISPLAY INVISIBLE (6175 2175);
FORCEADD AGND_SCSI..1
(5600 2925);
FORCEPROP 3 LASTPIN (5600 2975) SIG_NAME AGND_P3V3_STBY\g
J 0
(5610 2985);
DISPLAY 0.659574 (5610 2985);
PAINT MONO (5610 2985);
DISPLAY INVISIBLE (5610 2985);
FORCEPROP 1 LAST HDL_POWER AGND_P3V3_STBY
J 1
(5625 2850);
DISPLAY 0.617021 (5625 2850);
PAINT GREEN (5625 2850);
FORCEPROP 1 LAST VOLTAGE 0V
J 0
(5450 2950);
DISPLAY 1.021277 (5450 2950);
PAINT SKYBLUE (5450 2950);
DISPLAY INVISIBLE (5450 2950);
FORCEPROP 2 LAST CDS_LIB mstr_symbols
J 0
(5600 2925);
PAINT MONO (5600 2925);
DISPLAY INVISIBLE (5600 2925);
FORCEPROP 1 LAST BODY_TYPE PLUMBING
J 0
(5555 2882);
DISPLAY 0.340426 (5555 2882);
PAINT GREEN (5555 2882);
DISPLAY INVISIBLE (5555 2882);
FORCEPROP 1 LAST PATH I167
J 0
(5675 2925);
DISPLAY 0.872340 (5675 2925);
PAINT AQUA (5675 2925);
DISPLAY INVISIBLE (5675 2925);
FORCEADD AGND_SCSI..1
(9475 800);
FORCEPROP 3 LASTPIN (9475 850) SIG_NAME AGND_P3V3_STBY\g
J 0
(9485 860);
DISPLAY 0.659574 (9485 860);
PAINT MONO (9485 860);
DISPLAY INVISIBLE (9485 860);
FORCEPROP 1 LAST HDL_POWER AGND_P3V3_STBY
J 1
(9500 725);
DISPLAY 0.617021 (9500 725);
PAINT GREEN (9500 725);
FORCEPROP 1 LAST BODY_TYPE PLUMBING
J 0
(9430 757);
DISPLAY 0.340426 (9430 757);
PAINT GREEN (9430 757);
DISPLAY INVISIBLE (9430 757);
FORCEPROP 1 LAST VOLTAGE 0V
J 0
(9325 825);
DISPLAY 1.021277 (9325 825);
PAINT SKYBLUE (9325 825);
DISPLAY INVISIBLE (9325 825);
FORCEPROP 2 LAST CDS_LIB mstr_symbols
J 0
(9475 800);
PAINT MONO (9475 800);
DISPLAY INVISIBLE (9475 800);
FORCEPROP 1 LAST PATH I168
J 0
(9550 800);
DISPLAY 0.872340 (9550 800);
PAINT AQUA (9550 800);
DISPLAY INVISIBLE (9550 800);
FORCEADD AGND_SCSI..1
(10725 1625);
FORCEPROP 3 LASTPIN (10725 1675) SIG_NAME AGND_P3V3_STBY\g
J 0
(10735 1685);
DISPLAY 0.659574 (10735 1685);
PAINT MONO (10735 1685);
DISPLAY INVISIBLE (10735 1685);
FORCEPROP 1 LAST HDL_POWER AGND_P3V3_STBY
J 1
(10750 1550);
DISPLAY 0.617021 (10750 1550);
PAINT GREEN (10750 1550);
FORCEPROP 1 LAST VOLTAGE 0V
J 0
(10575 1650);
DISPLAY 1.021277 (10575 1650);
PAINT SKYBLUE (10575 1650);
DISPLAY INVISIBLE (10575 1650);
FORCEPROP 1 LAST BODY_TYPE PLUMBING
J 0
(10680 1582);
DISPLAY 0.340426 (10680 1582);
PAINT GREEN (10680 1582);
DISPLAY INVISIBLE (10680 1582);
FORCEPROP 2 LAST CDS_LIB mstr_symbols
J 0
(10725 1625);
PAINT MONO (10725 1625);
DISPLAY INVISIBLE (10725 1625);
FORCEPROP 1 LAST PATH I169
J 0
(10800 1625);
DISPLAY 0.872340 (10800 1625);
PAINT AQUA (10800 1625);
DISPLAY INVISIBLE (10800 1625);
FORCEADD CSD87384M..1
(9475 3425);
FORCEPROP 2 LASTPIN (9175 3325) $PN 4
J 2
(9165 3335);
DISPLAY 0.617021 (9165 3335);
PAINT ORANGE (9165 3335);
FORCEPROP 2 LASTPIN (9175 3425) $PN 1
J 2
(9165 3435);
DISPLAY 0.617021 (9165 3435);
PAINT ORANGE (9165 3435);
FORCEPROP 2 LASTPIN (9175 3525) $PN 2
J 2
(9165 3535);
DISPLAY 0.617021 (9165 3535);
PAINT ORANGE (9165 3535);
FORCEPROP 1 LAST PART_NUMBER H66258-001
J 0
(9225 3125);
DISPLAY 0.617021 (9225 3125);
PAINT BLUE (9225 3125);
FORCEPROP 1 LAST MATERIAL IC
J 0
(9225 3725);
DISPLAY 0.617021 (9225 3725);
PAINT SKYBLUE (9225 3725);
FORCEPROP 1 LAST LOCATION EU8E1
J 0
(9225 3775);
DISPLAY 0.617021 (9225 3775);
PAINT AQUA (9225 3775);
FORCEPROP 2 LASTPIN (9775 3275) $PN 3
J 0
(9785 3285);
DISPLAY 0.617021 (9785 3285);
PAINT ORANGE (9785 3285);
FORCEPROP 2 LASTPIN (9775 3375) $PN 5
J 0
(9785 3385);
DISPLAY 0.617021 (9785 3385);
PAINT ORANGE (9785 3385);
FORCEPROP 2 LAST CDS_LIB mstr_discrete
J 0
(9475 3425);
PAINT MONO (9475 3425);
DISPLAY INVISIBLE (9475 3425);
FORCEPROP 1 LAST PACK_TYPE SM
J 0
(9225 3825);
PAINT SKYBLUE (9225 3825);
DISPLAY INVISIBLE (9225 3825);
FORCEPROP 2 LAST SEC_TYPE SM
J 0
(9225 3825);
DISPLAY 1.021277 (9225 3825);
PAINT ORANGE (9225 3825);
DISPLAY INVISIBLE (9225 3825);
FORCEPROP 2 LAST SEC 1
J 0
(9225 3825);
DISPLAY 0.680851 (9225 3825);
PAINT MONO (9225 3825);
DISPLAY INVISIBLE (9225 3825);
FORCEPROP 2 LAST CDS_LOCATION EU8E1
J 0
(9225 3775);
DISPLAY 0.617021 (9225 3775);
PAINT AQUA (9225 3775);
DISPLAY INVISIBLE (9225 3775);
FORCEPROP 1 LAST PATH I170
J 0
(9525 3725);
PAINT GREEN (9525 3725);
DISPLAY INVISIBLE (9525 3725);
FORCEPROP 0 LAST ROOM P3V3_STBY_VR
J 0
(9225 3875);
DISPLAY 1.021277 (9225 3875);
PAINT ORANGE (9225 3875);
DISPLAY INVISIBLE (9225 3875);
FORCEADD RES..1
(7175 3825);
FORCEPROP 1 LASTPIN (7075 3825) $PN 1
J 0
(7087 3837);
DISPLAY 0.617021 (7087 3837);
PAINT ORANGE (7087 3837);
FORCEPROP 1 LAST WATTAGE 1/16W
J 2
(7150 3675);
DISPLAY 0.617021 (7150 3675);
PAINT SKYBLUE (7150 3675);
FORCEPROP 1 LAST VALUE 22.1
J 2
(7150 3725);
DISPLAY 0.617021 (7150 3725);
PAINT SKYBLUE (7150 3725);
FORCEPROP 1 LAST PART_NUMBER G21796-250
J 0
(7125 3925);
DISPLAY 0.617021 (7125 3925);
PAINT BLUE (7125 3925);
FORCEPROP 1 LAST LOCATION R8F10
J 0
(7125 3875);
DISPLAY 0.617021 (7125 3875);
PAINT AQUA (7125 3875);
FORCEPROP 1 LAST TOLERANCE 1.0%
J 0
(7175 3725);
DISPLAY 0.617021 (7175 3725);
PAINT SKYBLUE (7175 3725);
FORCEPROP 1 LAST MATERIAL CHIP
J 0
(7175 3675);
DISPLAY 0.617021 (7175 3675);
PAINT SKYBLUE (7175 3675);
FORCEPROP 1 LASTPIN (7275 3825) $PN 2
J 0
(7237 3837);
DISPLAY 0.617021 (7237 3837);
PAINT ORANGE (7237 3837);
FORCEPROP 1 LAST PACK_TYPE 0402
J 0
(7325 3725);
DISPLAY 0.617021 (7325 3725);
PAINT SKYBLUE (7325 3725);
FORCEPROP 0 LAST ROOM P3V3_STBY_VR
J 0
(7125 4025);
DISPLAY 1.021277 (7125 4025);
PAINT ORANGE (7125 4025);
DISPLAY INVISIBLE (7125 4025);
FORCEPROP 1 LAST PATH I171
J 0
(7125 3975);
DISPLAY 0.978723 (7125 3975);
PAINT WHITE (7125 3975);
DISPLAY INVISIBLE (7125 3975);
FORCEPROP 2 LAST CDS_LOCATION R8F10
J 0
(7125 3875);
DISPLAY 0.617021 (7125 3875);
PAINT AQUA (7125 3875);
DISPLAY INVISIBLE (7125 3875);
FORCEPROP 2 LAST SEC 1
J 0
(7125 4025);
DISPLAY 0.680851 (7125 4025);
PAINT MONO (7125 4025);
DISPLAY INVISIBLE (7125 4025);
FORCEPROP 2 LAST SEC_TYPE 0402
J 0
(7125 4025);
DISPLAY 1.021277 (7125 4025);
PAINT ORANGE (7125 4025);
DISPLAY INVISIBLE (7125 4025);
FORCEPROP 2 LAST CDS_LIB mstr_discrete
J 0
(7175 3825);
PAINT MONO (7175 3825);
DISPLAY INVISIBLE (7175 3825);
FORCEADD INDUCTOR..1
(10800 4050);
FORCEPROP 1 LASTPIN (10700 4050) $PN 1
J 0
(10700 4060);
DISPLAY 0.617021 (10700 4060);
PAINT WHITE (10700 4060);
FORCEPROP 1 LAST VALUE 1.00UH
J 2
(10795 3965);
DISPLAY 0.617021 (10795 3965);
PAINT SKYBLUE (10795 3965);
FORCEPROP 1 LAST MATERIAL IND
J 0
(10815 3965);
DISPLAY 0.617021 (10815 3965);
PAINT SKYBLUE (10815 3965);
FORCEPROP 1 LASTPIN (10900 4050) $PN 2
J 2
(10910 4060);
DISPLAY 0.617021 (10910 4060);
PAINT WHITE (10910 4060);
FORCEPROP 1 LAST PACK_TYPE SM
J 0
(11090 3965);
DISPLAY 0.617021 (11090 3965);
PAINT SKYBLUE (11090 3965);
FORCEPROP 1 LAST PART_NUMBER E98679-006
J 0
(10700 4150);
DISPLAY 0.617021 (10700 4150);
PAINT BLUE (10700 4150);
FORCEPROP 1 LAST LOCATION L8F1
J 0
(10700 4100);
DISPLAY 0.617021 (10700 4100);
PAINT AQUA (10700 4100);
FORCEPROP 2 LAST CDS_LIB mstr_discrete
J 0
(10800 4050);
PAINT MONO (10800 4050);
DISPLAY INVISIBLE (10800 4050);
FORCEPROP 1 LAST PATH I173
J 0
(10700 4200);
DISPLAY 0.978723 (10700 4200);
PAINT ORANGE (10700 4200);
DISPLAY INVISIBLE (10700 4200);
FORCEPROP 2 LAST CDS_LOCATION L8F1
J 0
(10700 4100);
DISPLAY 0.617021 (10700 4100);
PAINT AQUA (10700 4100);
DISPLAY INVISIBLE (10700 4100);
FORCEPROP 2 LAST $SEC 1
J 0
(10700 4250);
PAINT MONO (10700 4250);
DISPLAY INVISIBLE (10700 4250);
FORCEPROP 2 LAST CDS_SEC 1
J 0
(10700 4250);
PAINT MONO (10700 4250);
DISPLAY INVISIBLE (10700 4250);
FORCEADD CAP..1
(12425 3850);
FORCEPROP 1 LAST MATERIAL X6S
J 0
(12475 3750);
DISPLAY 0.617021 (12475 3750);
PAINT SKYBLUE (12475 3750);
FORCEPROP 1 LAST VOLTAGE 6.3V
J 0
(12475 3850);
DISPLAY 0.617021 (12475 3850);
PAINT SKYBLUE (12475 3850);
FORCEPROP 1 LAST PACK_TYPE 0805
J 0
(12475 3650);
DISPLAY 0.617021 (12475 3650);
PAINT SKYBLUE (12475 3650);
FORCEPROP 1 LAST TOLERANCE 20%
J 0
(12475 3800);
DISPLAY 0.617021 (12475 3800);
PAINT SKYBLUE (12475 3800);
FORCEPROP 1 LAST VALUE 22UF
J 0
(12475 3900);
DISPLAY 0.617021 (12475 3900);
PAINT SKYBLUE (12475 3900);
FORCEPROP 1 LAST PART_NUMBER C95333-008
J 0
(12475 3700);
DISPLAY 0.617021 (12475 3700);
PAINT BLUE (12475 3700);
FORCEPROP 1 LAST LOCATION C2T9
J 0
(12475 3950);
DISPLAY 0.617021 (12475 3950);
PAINT AQUA (12475 3950);
FORCEPROP 1 LASTPIN (12425 3750) $PN 2
J 0
(12435 3730);
DISPLAY 0.787234 (12435 3730);
PAINT ORANGE (12435 3730);
DISPLAY INVISIBLE (12435 3730);
FORCEPROP 1 LASTPIN (12425 3950) $PN 1
J 0
(12435 3930);
DISPLAY 0.787234 (12435 3930);
PAINT ORANGE (12435 3930);
DISPLAY INVISIBLE (12435 3930);
FORCEPROP 2 LAST ROOM P3V3_STBY_VR
J 0
(12425 3850);
PAINT GREEN (12425 3850);
DISPLAY INVISIBLE (12425 3850);
FORCEPROP 2 LAST CDS_LIB mstr_discrete
J 0
(12425 3850);
PAINT MONO (12425 3850);
DISPLAY INVISIBLE (12425 3850);
FORCEPROP 2 LAST BOM_COST P3V3_STBY_VR
J 0
(12425 3850);
PAINT WHITE (12425 3850);
DISPLAY INVISIBLE (12425 3850);
FORCEPROP 2 LAST CDS_LOCATION C2T9
J 0
(12475 3950);
DISPLAY 0.617021 (12475 3950);
PAINT AQUA (12475 3950);
DISPLAY INVISIBLE (12475 3950);
FORCEPROP 2 LAST REUSE_ID 33
J 0
(12475 4050);
DISPLAY 1.042553 (12475 4050);
PAINT ORANGE (12475 4050);
DISPLAY INVISIBLE (12475 4050);
FORCEPROP 2 LAST CDS_SEC 1
J 0
(12475 4050);
PAINT MONO (12475 4050);
DISPLAY INVISIBLE (12475 4050);
FORCEPROP 2 LAST $SEC 1
J 0
(12475 4050);
PAINT MONO (12475 4050);
DISPLAY INVISIBLE (12475 4050);
FORCEPROP 1 LAST PATH I174
J 0
(12475 4000);
DISPLAY 0.978723 (12475 4000);
PAINT WHITE (12475 4000);
DISPLAY INVISIBLE (12475 4000);
FORCEADD GND..1
(12425 3575);
FORCEPROP 3 LASTPIN (12425 3625) SIG_NAME GND\g
J 0
(12435 3635);
DISPLAY 0.659574 (12435 3635);
PAINT MONO (12435 3635);
DISPLAY INVISIBLE (12435 3635);
FORCEPROP 2 LAST BOM_COST PVPP_KLM_VR
J 0
(11575 3650);
DISPLAY 1.042553 (11575 3650);
PAINT WHITE (11575 3650);
DISPLAY INVISIBLE (11575 3650);
FORCEPROP 2 LAST ROOM PVPP_KLM_VR
J 0
(11850 3650);
DISPLAY 1.042553 (11850 3650);
PAINT GREEN (11850 3650);
DISPLAY INVISIBLE (11850 3650);
FORCEPROP 1 LAST BODY_TYPE PLUMBING
J 0
(12380 3532);
DISPLAY 0.340426 (12380 3532);
PAINT GREEN (12380 3532);
DISPLAY INVISIBLE (12380 3532);
FORCEPROP 1 LAST SIZE 1B
J 0
(12500 3525);
DISPLAY 0.872340 (12500 3525);
PAINT GREEN (12500 3525);
DISPLAY INVISIBLE (12500 3525);
FORCEPROP 1 LAST PATH I175
J 0
(12500 3575);
DISPLAY 0.872340 (12500 3575);
PAINT AQUA (12500 3575);
DISPLAY INVISIBLE (12500 3575);
FORCEPROP 2 LAST CDS_LIB mstr_symbols
J 0
(12425 3575);
PAINT MONO (12425 3575);
DISPLAY INVISIBLE (12425 3575);
FORCEPROP 1 LAST VOLTAGE 0
J 0
(12425 3575);
PAINT SKYBLUE (12425 3575);
DISPLAY INVISIBLE (12425 3575);
FORCEPROP 1 LAST HDL_POWER GND
J 0
(12425 3725);
DISPLAY 0.872340 (12425 3725);
PAINT GREEN (12425 3725);
DISPLAY INVISIBLE (12425 3725);
FORCEADD RES..1
(6525 2725);
FORCEPROP 1 LAST WATTAGE 1/16W
J 2
(6500 2575);
DISPLAY 0.617021 (6500 2575);
PAINT SKYBLUE (6500 2575);
FORCEPROP 1 LAST VALUE 0.0
J 2
(6425 2625);
DISPLAY 0.617021 (6425 2625);
PAINT SKYBLUE (6425 2625);
FORCEPROP 1 LAST MATERIAL CHIP
J 0
(6525 2575);
DISPLAY 0.617021 (6525 2575);
PAINT SKYBLUE (6525 2575);
FORCEPROP 1 LAST TOLERANCE 5%
J 0
(6475 2625);
DISPLAY 0.617021 (6475 2625);
PAINT SKYBLUE (6475 2625);
FORCEPROP 1 LAST LOCATION R8F2
J 0
(6475 2775);
DISPLAY 0.617021 (6475 2775);
PAINT AQUA (6475 2775);
FORCEPROP 1 LAST PACK_TYPE 0402
J 0
(6600 2625);
DISPLAY 0.617021 (6600 2625);
PAINT SKYBLUE (6600 2625);
FORCEPROP 1 LAST PART_NUMBER G21497-005
J 0
(6375 2675);
DISPLAY 0.617021 (6375 2675);
PAINT BLUE (6375 2675);
FORCEPROP 2 LAST CDS_LOCATION R8F2
J 0
(6475 2775);
DISPLAY 0.617021 (6475 2775);
PAINT AQUA (6475 2775);
DISPLAY INVISIBLE (6475 2775);
FORCEPROP 2 LAST CDS_LIB mstr_discrete
J 0
(6525 2725);
PAINT ORANGE (6525 2725);
DISPLAY INVISIBLE (6525 2725);
FORCEPROP 1 LASTPIN (6425 2725) $PN 1
J 0
(6437 2737);
DISPLAY 0.787234 (6437 2737);
PAINT ORANGE (6437 2737);
DISPLAY INVISIBLE (6437 2737);
FORCEPROP 1 LASTPIN (6625 2725) $PN 2
J 0
(6587 2737);
DISPLAY 0.787234 (6587 2737);
PAINT ORANGE (6587 2737);
DISPLAY INVISIBLE (6587 2737);
FORCEPROP 2 LAST CDS_SEC 1
J 0
(6475 2925);
PAINT MONO (6475 2925);
DISPLAY INVISIBLE (6475 2925);
FORCEPROP 2 LAST $SEC 1
J 0
(6475 2925);
PAINT MONO (6475 2925);
DISPLAY INVISIBLE (6475 2925);
FORCEPROP 1 LAST PATH I176
J 0
(6475 2875);
DISPLAY 0.978723 (6475 2875);
PAINT WHITE (6475 2875);
DISPLAY INVISIBLE (6475 2875);
FORCEPROP 2 LAST ROOM PVCCIN_CPU0_VR
J 0
(6475 2825);
DISPLAY 1.361702 (6475 2825);
PAINT ORANGE (6475 2825);
DISPLAY INVISIBLE (6475 2825);
FORCEADD RES..2
(6950 3250);
FORCEPROP 1 LAST WATTAGE 1/16W
J 0
(6990 3225);
DISPLAY 0.617021 (6990 3225);
PAINT SKYBLUE (6990 3225);
FORCEPROP 1 LAST PACK_TYPE 0402
J 0
(6990 3075);
DISPLAY 0.617021 (6990 3075);
PAINT SKYBLUE (6990 3075);
FORCEPROP 1 LAST TOLERANCE 1%
J 0
(6995 3275);
DISPLAY 0.617021 (6995 3275);
PAINT SKYBLUE (6995 3275);
FORCEPROP 1 LAST MATERIAL EMPTY
J 0
(6990 3175);
DISPLAY 0.617021 (6990 3175);
PAINT RED (6990 3175);
FORCEPROP 1 LAST LOCATION R8E40
J 0
(6995 3375);
DISPLAY 0.617021 (6995 3375);
PAINT AQUA (6995 3375);
FORCEPROP 1 LAST VALUE 100.0K
J 0
(6995 3325);
DISPLAY 0.617021 (6995 3325);
PAINT SKYBLUE (6995 3325);
FORCEPROP 1 LAST PART_NUMBER G21796-010
J 0
(6990 3125);
DISPLAY 0.617021 (6990 3125);
PAINT BLUE (6990 3125);
FORCEPROP 1 LASTPIN (6950 3150) $PN 2
J 0
(6955 3160);
DISPLAY 0.787234 (6955 3160);
PAINT ORANGE (6955 3160);
DISPLAY INVISIBLE (6955 3160);
FORCEPROP 2 LAST CDS_LIB mstr_discrete
J 0
(6950 3250);
PAINT ORANGE (6950 3250);
DISPLAY INVISIBLE (6950 3250);
FORCEPROP 1 LASTPIN (6950 3350) $PN 1
J 0
(6955 3312);
DISPLAY 0.787234 (6955 3312);
PAINT ORANGE (6955 3312);
DISPLAY INVISIBLE (6955 3312);
FORCEPROP 2 LAST CDS_LOCATION R8E40
J 0
(6995 3375);
DISPLAY 0.617021 (6995 3375);
PAINT AQUA (6995 3375);
DISPLAY INVISIBLE (6995 3375);
FORCEPROP 1 LAST PATH I177
J 0
(7000 3425);
DISPLAY 0.978723 (7000 3425);
PAINT WHITE (7000 3425);
DISPLAY INVISIBLE (7000 3425);
FORCEPROP 0 LAST ROOM BMC
J 0
(7000 3475);
DISPLAY 0.617021 (7000 3475);
PAINT ORANGE (7000 3475);
DISPLAY INVISIBLE (7000 3475);
FORCEPROP 2 LAST $SEC 1
J 0
(7000 3475);
PAINT MONO (7000 3475);
DISPLAY INVISIBLE (7000 3475);
FORCEPROP 2 LAST CDS_SEC 1
J 0
(7000 3475);
PAINT MONO (7000 3475);
DISPLAY INVISIBLE (7000 3475);
FORCEPROP 0 LAST BOM_COST SM_CONTROLLER
J 0
(7000 3575);
DISPLAY 1.021277 (7000 3575);
PAINT ORANGE (7000 3575);
DISPLAY INVISIBLE (7000 3575);
FORCEADD P3V3_STBY..1
(6950 3500);
FORCEPROP 3 LASTPIN (6950 3450) SIG_NAME P3V3_STBY\g
J 0
(6960 3460);
DISPLAY 0.659574 (6960 3460);
PAINT MONO (6960 3460);
DISPLAY INVISIBLE (6960 3460);
FORCEPROP 1 LAST HDL_POWER P3V3_STBY
J 0
(6650 3375);
DISPLAY 0.872340 (6650 3375);
PAINT ORANGE (6650 3375);
DISPLAY INVISIBLE (6650 3375);
FORCEPROP 1 LAST BODY_TYPE PLUMBING
J 0
(6905 3457);
DISPLAY 0.340426 (6905 3457);
PAINT GREEN (6905 3457);
DISPLAY INVISIBLE (6905 3457);
FORCEPROP 1 LAST PATH I178
J 0
(6995 3502);
DISPLAY 0.340426 (6995 3502);
PAINT GREEN (6995 3502);
DISPLAY INVISIBLE (6995 3502);
FORCEPROP 2 LAST CDS_LIB mstr_symbols
J 0
(6950 3500);
PAINT ORANGE (6950 3500);
DISPLAY INVISIBLE (6950 3500);
FORCEPROP 1 LAST SIZE 1B
J 0
(6995 3522);
DISPLAY 0.340426 (6995 3522);
PAINT GREEN (6995 3522);
DISPLAY INVISIBLE (6995 3522);
FORCEPROP 1 LAST VOLTAGE +3.3V
J 0
(7150 3650);
DISPLAY 1.021277 (7150 3650);
PAINT SKYBLUE (7150 3650);
DISPLAY INVISIBLE (7150 3650);
FORCEADD P3V3_STBY..1
(12575 4225);
FORCEPROP 3 LASTPIN (12575 4175) SIG_NAME P3V3_STBY\g
J 0
(12585 4185);
DISPLAY 0.659574 (12585 4185);
PAINT MONO (12585 4185);
DISPLAY INVISIBLE (12585 4185);
FORCEPROP 1 LAST HDL_POWER P3V3_STBY
J 0
(12275 4100);
DISPLAY 0.872340 (12275 4100);
PAINT ORANGE (12275 4100);
DISPLAY INVISIBLE (12275 4100);
FORCEPROP 1 LAST PATH I85
J 0
(12620 4227);
DISPLAY 0.340426 (12620 4227);
PAINT GREEN (12620 4227);
DISPLAY INVISIBLE (12620 4227);
FORCEPROP 1 LAST BODY_TYPE PLUMBING
J 0
(12530 4182);
DISPLAY 0.340426 (12530 4182);
PAINT GREEN (12530 4182);
DISPLAY INVISIBLE (12530 4182);
FORCEPROP 2 LAST CDS_LIB mstr_symbols
J 0
(12575 4225);
PAINT ORANGE (12575 4225);
DISPLAY INVISIBLE (12575 4225);
FORCEPROP 1 LAST SIZE 1B
J 0
(12620 4247);
DISPLAY 0.340426 (12620 4247);
PAINT GREEN (12620 4247);
DISPLAY INVISIBLE (12620 4247);
FORCEPROP 1 LAST VOLTAGE +3.3V
J 0
(12775 4375);
DISPLAY 1.021277 (12775 4375);
PAINT SKYBLUE (12775 4375);
DISPLAY INVISIBLE (12775 4375);
FORCEADD DNS..2
(10455 3545);
PAINT RED (10455 3545);
FORCEPROP 1 LAST COMMENT_BODY TRUE
R 1
J 0
(10530 3320);
DISPLAY 0.872340 (10530 3320);
PAINT GREEN (10530 3320);
DISPLAY INVISIBLE (10530 3320);
FORCEPROP 2 LAST CDS_LIB mstr_misc
J 0
(10455 3545);
PAINT ORANGE (10455 3545);
DISPLAY INVISIBLE (10455 3545);
FORCEADD INTEL_CORP_BPAGE..1
(12800 175);
FORCEPROP 1 LAST CDS_CON_LAST_MODIFIED Tue Dec 01 11:52:31 2015
J 0
(11375 500);
PAINT ORANGE (11375 500);
DISPLAY INVISIBLE (11375 500);
FORCEPROP 1 LAST CUSTOM_TXT_CDS <CURRENT_DESIGN_SHEET> OF <TOTAL_DESIGN_SHEETS>
J 0
(12300 200);
PAINT GREEN (12300 200);
FORCEPROP 1 LAST CUSTOM_TXT_CDS <CON_LAST_MODIFIED>
J 0
(10875 525);
PAINT GREEN (10875 525);
FORCEPROP 2 LAST CUSTOM_TXT_CDS <XR_PAGE_TITLE>
J 0
(4910 5425);
DISPLAY 0.638298 (4910 5425);
PAINT PINK (4910 5425);
DISPLAY INVISIBLE (4910 5425);
FORCEPROP 1 LAST SCH_TITLE P3V3 STBY VR
J 0
(4850 225);
DISPLAY 1.212766 (4850 225);
PAINT ORANGE (4850 225);
FORCEPROP 1 LAST SCH_ADDRESS1 2200 Mission College Blvd.
J 0
(8825 300);
DISPLAY 0.617021 (8825 300);
PAINT GREEN (8825 300);
FORCEPROP 1 LAST SCH_ADDRESS2 P.O. BOX 58119
J 0
(8825 250);
DISPLAY 0.617021 (8825 250);
PAINT GREEN (8825 250);
FORCEPROP 1 LAST SCH_ADDRESS3 Santa Clara, CA 95052-8119
J 0
(8825 200);
DISPLAY 0.617021 (8825 200);
PAINT GREEN (8825 200);
FORCEPROP 1 LAST SCH_NUMBER H4694802
J 0
(11500 325);
DISPLAY 1.212766 (11500 325);
PAINT YELLOW (11500 325);
FORCEPROP 1 LAST SCH_DEPT BESD
J 1
(8350 275);
DISPLAY 1.212766 (8350 275);
PAINT YELLOW (8350 275);
FORCEPROP 1 LAST SCH_REV 2.420
J 0
(12550 325);
DISPLAY 0.978723 (12550 325);
PAINT YELLOW (12550 325);
FORCEPROP 2 LAST PAGE_BORDER TRUE
J 0
(4910 5425);
DISPLAY 0.851064 (4910 5425);
PAINT PINK (4910 5425);
DISPLAY INVISIBLE (4910 5425);
FORCEPROP 1 LAST COMMENT_BODY TRUE
J 0
(12812 187);
DISPLAY 0.468085 (12812 187);
PAINT GREEN (12812 187);
DISPLAY INVISIBLE (12812 187);
FORCEPROP 2 LAST CDS_LIB mstr_symbols
J 0
(12800 175);
PAINT MONO (12800 175);
DISPLAY INVISIBLE (12800 175);
FORCEPROP 2 LAST CDS_XR_PAGE_TITLE CR-240 : @BASEBOARD_FAB2_LIB.BASEBOARD_FAB2(SCH_1):PAGE240
J 0
(4910 5425);
DISPLAY 0.638298 (4910 5425);
PAINT PINK (4910 5425);
DISPLAY INVISIBLE (4910 5425);
FORCEADD DNS..2
(10455 3895);
PAINT RED (10455 3895);
FORCEPROP 1 LAST COMMENT_BODY TRUE
R 1
J 0
(10530 3670);
DISPLAY 0.872340 (10530 3670);
PAINT GREEN (10530 3670);
DISPLAY INVISIBLE (10530 3670);
FORCEPROP 2 LAST CDS_LIB mstr_misc
J 0
(10455 3895);
PAINT ORANGE (10455 3895);
DISPLAY INVISIBLE (10455 3895);
FORCEADD DNS..2
(6955 3245);
PAINT RED (6955 3245);
FORCEPROP 1 LAST COMMENT_BODY TRUE
R 1
J 0
(7030 3020);
DISPLAY 0.872340 (7030 3020);
PAINT GREEN (7030 3020);
DISPLAY INVISIBLE (7030 3020);
FORCEPROP 2 LAST CDS_LIB mstr_misc
J 0
(6955 3245);
PAINT ORANGE (6955 3245);
DISPLAY INVISIBLE (6955 3245);
FORCEADD DNS..2
(6180 2470);
PAINT RED (6180 2470);
FORCEPROP 1 LAST COMMENT_BODY TRUE
R 1
J 0
(6255 2245);
DISPLAY 0.872340 (6255 2245);
PAINT GREEN (6255 2245);
DISPLAY INVISIBLE (6255 2245);
FORCEPROP 2 LAST CDS_LIB mstr_misc
J 0
(6180 2470);
PAINT ORANGE (6180 2470);
DISPLAY INVISIBLE (6180 2470);
FORCEADD DNS..2
(5630 2395);
PAINT RED (5630 2395);
FORCEPROP 1 LAST COMMENT_BODY TRUE
R 1
J 0
(5705 2170);
DISPLAY 0.872340 (5705 2170);
PAINT GREEN (5705 2170);
DISPLAY INVISIBLE (5705 2170);
FORCEPROP 2 LAST CDS_LIB mstr_misc
J 0
(5630 2395);
PAINT ORANGE (5630 2395);
DISPLAY INVISIBLE (5630 2395);
FORCEADD DESIGN_NOTE..1
(11450 4875);
FORCEPROP 1 LAST COMMENT_BODY TRUE
J 0
(11475 4975);
DISPLAY 1.361702 (11475 4975);
PAINT WHITE (11475 4975);
DISPLAY INVISIBLE (11475 4975);
FORCEPROP 2 LAST CDS_LIB mstr_symbols
J 0
(11450 4875);
DISPLAY 1.021277 (11450 4875);
PAINT WHITE (11450 4875);
DISPLAY INVISIBLE (11450 4875);
WIRE 16 -1 (5625 2200)(5625 2300);
WIRE 16 -1 (7150 2875)(6025 2875);
WIRE 16 -1 (6025 2875)(6025 3500);
WIRE 16 -1 (6025 3500)(5725 3500);
WIRE 16 -1 (5600 3500)(5725 3500);
WIRE 16 -1 (5725 3500)(5725 3550);
WIRE 16 -1 (5600 3400)(5600 3500);
WIRE 16 -1 (6350 3250)(6350 3150);
WIRE 16 -1 (8150 4075)(8150 4250);
WIRE 16 -1 (6275 4100)(6275 4000);
WIRE 16 -1 (6750 4500)(6800 4500);
WIRE 16 -1 (6750 4600)(6750 4500);
WIRE 16 -1 (10175 1725)(10375 1725);
WIRE 16 -1 (10175 1675)(10175 1725);
WIRE 16 -1 (9875 3125)(9875 3275);
WIRE 16 -1 (9875 3275)(9775 3275);
WIRE 16 -1 (10450 3450)(10450 3400);
WIRE 16 -1 (11025 3675)(11025 3775);
WIRE 16 -1 (11350 3700)(11350 3775);
WIRE 16 -1 (11675 3700)(11675 3775);
WIRE 16 -1 (11950 3650)(11950 3775);
WIRE 16 -1 (12175 3650)(12175 3750);
WIRE 16 -1 (7150 2675)(6975 2675);
WIRE 16 -1 (6975 2675)(6975 2425);
WIRE 16 -1 (7150 2425)(6975 2425);
WIRE 16 -1 (6975 2425)(6975 2375);
WIRE 16 -1 (7150 2375)(6975 2375);
WIRE 16 -1 (6975 2375)(6975 2150);
WIRE 16 -1 (6425 1750)(6425 1600);
WIRE 16 -1 (6175 2225)(6175 2375);
WIRE 16 -1 (5600 3200)(5600 2975);
WIRE 16 -1 (9325 925)(9475 925);
WIRE 16 -1 (9475 925)(9475 1000);
WIRE 16 -1 (9475 925)(9475 850);
WIRE 16 -1 (10725 1675)(10725 1725);
WIRE 16 -1 (10725 1725)(10575 1725);
WIRE 16 -1 (12425 3750)(12425 3625);
WIRE 16 -1 (6950 3350)(6950 3450);
WIRE 16 -1 (11025 3975)(11025 4050);
WIRE 16 -1 (11025 4050)(11350 4050);
WIRE 16 -1 (10900 4050)(11025 4050);
WIRE 16 -1 (11350 4050)(11675 4050);
WIRE 16 -1 (11350 4050)(11350 3975);
WIRE 16 -1 (11675 3975)(11675 4050);
WIRE 16 -1 (11675 4050)(11950 4050);
WIRE 16 -1 (11950 4050)(12175 4050);
WIRE 16 -1 (11950 4050)(11950 3975);
WIRE 16 -1 (12425 4050)(12175 4050);
WIRE 16 -1 (12175 4050)(12175 3950);
WIRE 16 -1 (12425 3950)(12425 4050);
WIRE 16 -1 (12575 4050)(12425 4050);
WIRE 16 -1 (12575 4050)(12575 2025);
WIRE 16 -1 (12575 4175)(12575 4050);
WIRE 16 -1 (9475 2025)(12575 2025);
WIRE 16 -1 (9475 2025)(9475 1925);
WIRE 16 682 (12025 4325)(12025 4950);
WIRE 16 682 (11225 4325)(12025 4325);
WIRE 16 682 (12025 4950)(11225 4950);
WIRE 16 682 (11225 4950)(11225 4325);
WIRE 16 -1 (8750 4500)(8750 3525);
WIRE 16 -1 (8150 4500)(8750 4500);
WIRE 16 -1 (8750 3525)(9175 3525);
WIRE 16 -1 (8150 4450)(8150 4500);
WIRE 16 -1 (7825 4500)(8150 4500);
WIRE 16 -1 (7825 4425)(7825 4500);
WIRE 16 -1 (7475 4500)(7825 4500);
WIRE 16 -1 (7475 4425)(7475 4500);
WIRE 16 -1 (7125 4500)(7475 4500);
FORCEPROP 0 LAST SIG_NAME VR_FET_SW_P12V_STBY_P3V3_STBY
J 0
(7190 4510);
DISPLAY 0.617021 (7190 4510);
PAINT ORANGE (7190 4510);
FORCEPROP 2 LASTPROP $XRERR UNIQUE?
J 0
(6950 4510);
DISPLAY 0.638298 (6950 4510);
PAINT MONO (6950 4510);
DISPLAY INVISIBLE (6950 4510);
WIRE 16 -1 (7125 4425)(7125 4500);
WIRE 16 -1 (7000 4500)(7125 4500);
WIRE 16 -1 (10450 4000)(10450 4050);
WIRE 16 -1 (10700 4050)(10450 4050);
WIRE 16 -1 (10175 4050)(10450 4050);
WIRE 16 -1 (10175 4050)(10175 3375);
WIRE 16 -1 (8450 4050)(10175 4050);
FORCEPROP 2 LAST SIG_NAME VR_P3V3_STBY_PHASE
J 0
(8840 4060);
DISPLAY 0.617021 (8840 4060);
PAINT ORANGE (8840 4060);
FORCEPROP 2 LASTPROP $XRERR UNIQUE?
J 0
(8600 4060);
DISPLAY 0.638298 (8600 4060);
PAINT MONO (8600 4060);
DISPLAY INVISIBLE (8600 4060);
WIRE 16 -1 (8450 4050)(8450 3425);
WIRE 16 -1 (10175 3375)(9775 3375);
WIRE 16 -1 (8400 3425)(8450 3425);
WIRE 16 -1 (8450 2675)(8450 3425);
WIRE 16 -1 (7950 2675)(8450 2675);
WIRE 16 -1 (10450 3650)(10450 3800);
FORCEPROP 2 LAST SIG_NAME VR_P3V3_STBY_SNUB
J 0
(10465 3710);
DISPLAY 0.617021 (10465 3710);
PAINT ORANGE (10465 3710);
FORCEPROP 2 LASTPROP $XRERR UNIQUE?
J 0
(10225 3710);
DISPLAY 0.638298 (10225 3710);
PAINT MONO (10225 3710);
DISPLAY INVISIBLE (10225 3710);
WIRE 16 -1 (8800 3325)(9175 3325);
WIRE 16 -1 (8800 2575)(8800 3325);
WIRE 16 -1 (7950 2575)(8800 2575);
FORCEPROP 2 LAST SIG_NAME VR_P3V3_STBY_LGATE
J 0
(8165 2585);
DISPLAY 0.617021 (8165 2585);
PAINT ORANGE (8165 2585);
FORCEPROP 2 LASTPROP $XRERR UNIQUE?
J 0
(7925 2585);
DISPLAY 0.638298 (7925 2585);
PAINT MONO (7925 2585);
DISPLAY INVISIBLE (7925 2585);
WIRE 16 -1 (8575 3425)(9175 3425);
WIRE 16 -1 (8575 2775)(8575 3425);
WIRE 16 -1 (7950 2775)(8575 2775);
FORCEPROP 2 LAST SIG_NAME VR_P3V3_STBY_UGATE
J 0
(8090 2785);
DISPLAY 0.617021 (8090 2785);
PAINT ORANGE (8090 2785);
FORCEPROP 2 LASTPROP $XRERR UNIQUE?
J 0
(7850 2785);
DISPLAY 0.638298 (7850 2785);
PAINT MONO (7850 2785);
DISPLAY INVISIBLE (7850 2785);
WIRE 16 2175 (8500 3600)(8500 3225);
WIRE 16 2175 (7275 3600)(8500 3600);
WIRE 16 2175 (8500 3225)(7275 3225);
WIRE 16 2175 (7275 3225)(7275 3600);
WIRE 16 -1 (7950 2475)(8400 2475);
WIRE 16 -1 (8400 2475)(8400 1250);
WIRE 16 -1 (8400 1250)(9475 1250);
FORCEPROP 0 LAST SIG_NAME VSENSE_VOUT_P3V3_STBY
J 0
(8415 1260);
DISPLAY 0.617021 (8415 1260);
PAINT ORANGE (8415 1260);
FORCEPROP 2 LASTPROP $XRERR UNIQUE?
J 0
(8175 1260);
DISPLAY 0.638298 (8175 1260);
PAINT MONO (8175 1260);
DISPLAY INVISIBLE (8175 1260);
WIRE 16 -1 (9475 1325)(9475 1250);
WIRE 16 -1 (9475 1250)(9475 1200);
WIRE 16 -1 (7950 2375)(8275 2375);
WIRE 16 -1 (8275 2375)(8275 925);
WIRE 16 -1 (9125 925)(8275 925);
FORCEPROP 2 LAST SIG_NAME VSENSE_RGND_P3V3_STBY
J 0
(8290 935);
DISPLAY 0.617021 (8290 935);
PAINT ORANGE (8290 935);
FORCEPROP 2 LASTPROP $XRERR UNIQUE?
J 0
(8050 935);
DISPLAY 0.638298 (8050 935);
PAINT MONO (8050 935);
DISPLAY INVISIBLE (8050 935);
WIRE 16 2175 (9400 1950)(9775 1950);
WIRE 16 2175 (9400 900)(9400 1950);
WIRE 16 2175 (9775 1950)(9775 900);
WIRE 16 2175 (9400 900)(9775 900);
WIRE 16 -1 (9475 1525)(9475 1725);
FORCEPROP 0 LAST SIG_NAME VSENSE_P3V3_STBY
R 1
J 0
(9465 1485);
DISPLAY 0.617021 (9465 1485);
PAINT ORANGE (9465 1485);
FORCEPROP 2 LASTPROP $XRERR UNIQUE?
J 0
(9225 1485);
DISPLAY 0.638298 (9225 1485);
PAINT MONO (9225 1485);
DISPLAY INVISIBLE (9225 1485);
WIRE 16 -1 (8200 3425)(7700 3425);
FORCEPROP 2 LAST SIG_NAME VR_P3V3_STBY_BOOT_R
J 0
(7720 3435);
DISPLAY 0.617021 (7720 3435);
PAINT ORANGE (7720 3435);
FORCEPROP 2 LASTPROP $XRERR UNIQUE?
J 0
(7480 3435);
DISPLAY 0.638298 (7480 3435);
PAINT MONO (7480 3435);
DISPLAY INVISIBLE (7480 3435);
WIRE 16 2175 (8075 4550)(8075 4100);
WIRE 16 2175 (7075 4550)(8075 4550);
WIRE 16 2175 (8075 4100)(7075 4100);
WIRE 16 2175 (7075 4100)(7075 4550);
WIRE 16 -1 (7375 3125)(8000 3125);
WIRE 16 -1 (7375 3425)(7375 3125);
FORCEPROP 2 LAST SIG_NAME VR_P3V3_STBY_BOOT
J 0
(7465 3160);
DISPLAY 0.617021 (7465 3160);
PAINT ORANGE (7465 3160);
FORCEPROP 2 LASTPROP $XRERR UNIQUE?
J 0
(7225 3160);
DISPLAY 0.638298 (7225 3160);
PAINT MONO (7225 3160);
DISPLAY INVISIBLE (7225 3160);
WIRE 16 -1 (8000 3125)(8000 2875);
WIRE 16 -1 (8000 2875)(7950 2875);
WIRE 16 -1 (7500 3425)(7375 3425);
WIRE 16 -1 (7775 3825)(7275 3825);
FORCEPROP 2 LAST SIG_NAME PWRGD_P3V3_STBY
J 0
(7340 3835);
DISPLAY 0.617021 (7340 3835);
PAINT ORANGE (7340 3835);
WIRE 16 -1 (7075 3825)(6350 3825);
FORCEPROP 2 LAST SIG_NAME PWRGD_P3V3_STBY_R
J 0
(6515 3835);
DISPLAY 0.617021 (6515 3835);
PAINT ORANGE (6515 3835);
FORCEPROP 2 LASTPROP $XRERR UNIQUE?
J 0
(6275 3835);
DISPLAY 0.638298 (6275 3835);
PAINT MONO (6275 3835);
DISPLAY INVISIBLE (6275 3835);
WIRE 16 -1 (6350 3825)(6350 3600);
WIRE 16 -1 (6350 3600)(6275 3600);
WIRE 16 -1 (6350 3450)(6350 3600);
WIRE 16 -1 (6275 3800)(6275 3600);
WIRE 16 -1 (6175 3600)(6275 3600);
WIRE 16 -1 (6175 2825)(6175 3600);
WIRE 16 -1 (7150 2825)(6175 2825);
WIRE 16 -1 (6950 2725)(6950 3150);
WIRE 16 -1 (7150 2725)(6950 2725);
WIRE 16 -1 (6950 2725)(6625 2725);
FORCEPROP 2 LAST SIG_NAME VR_P3V3_STBY_EN
J 0
(6615 2735);
DISPLAY 0.617021 (6615 2735);
PAINT ORANGE (6615 2735);
FORCEPROP 2 LASTPROP $XRERR UNIQUE?
J 0
(6375 2735);
DISPLAY 0.638298 (6375 2735);
PAINT MONO (6375 2735);
DISPLAY INVISIBLE (6375 2735);
WIRE 16 -1 (6425 2325)(7150 2325);
FORCEPROP 2 LAST SIG_NAME VR_P3V3_STBY_OCSELECT
J 0
(6440 2335);
DISPLAY 0.617021 (6440 2335);
PAINT ORANGE (6440 2335);
FORCEPROP 2 LASTPROP $XRERR UNIQUE?
J 0
(6200 2335);
DISPLAY 0.638298 (6200 2335);
PAINT MONO (6200 2335);
DISPLAY INVISIBLE (6200 2335);
WIRE 16 -1 (6425 1950)(6425 2325);
WIRE 16 -1 (6175 2575)(6175 2725);
WIRE 16 -1 (6425 2725)(6175 2725);
WIRE 16 -1 (5625 2725)(6175 2725);
WIRE 16 -1 (5225 2725)(5625 2725);
FORCEPROP 2 LAST SIG_NAME PWRGD_P5V_STBY
J 0
(5216 2747);
DISPLAY 0.617021 (5216 2747);
PAINT ORANGE (5216 2747);
WIRE 16 -1 (5625 2500)(5625 2725);
DOT 1 (5625 2725);
DOT 1 (5725 3500);
DOT 1 (6175 2725);
DOT 1 (6975 2375);
DOT 1 (6975 2425);
DOT 1 (6950 2725);
DOT 1 (6275 3600);
DOT 1 (6350 3600);
DOT 1 (7125 4500);
DOT 1 (7475 4500);
DOT 1 (7825 4500);
DOT 1 (8150 4500);
DOT 1 (9475 925);
DOT 1 (9475 1250);
DOT 1 (8450 3425);
DOT 1 (10175 4050);
DOT 1 (10450 4050);
DOT 1 (11025 4050);
DOT 1 (11350 4050);
DOT 1 (11675 4050);
DOT 1 (11950 4050);
DOT 1 (12175 4050);
DOT 1 (12425 4050);
DOT 1 (12575 4050);
FORCENOTE
10MIL WIDTH
(9180 530) 0;
DISPLAY LEFT (9180 530);
DISPLAY 0.808511 (9180 530);
PAINT PURPLE (9180 530);
FORCENOTE
BOM_COST: P3V3_STBY_VR
(5675 225) 0;
DISPLAY LEFT (5675 225);
DISPLAY 0.787234 (5675 225);
PAINT PURPLE (5675 225);
FORCENOTE
ROOM = P3V3_STBY_VR
(5675 275) 0;
DISPLAY LEFT (5675 275);
DISPLAY 0.787234 (5675 275);
PAINT PURPLE (5675 275);
FORCENOTE
37A OC
(5980 1830) 0;
DISPLAY LEFT (5980 1830);
PAINT PURPLE (5980 1830);
FORCENOTE
SPOF
(7275 3625) 0;
DISPLAY LEFT (7275 3625);
DISPLAY 1.659574 (7275 3625);
PAINT PURPLE (7275 3625);
FORCENOTE
PLACE ON
(7575 3650) 0;
DISPLAY LEFT (7575 3650);
DISPLAY 1.042553 (7575 3650);
PAINT PURPLE (7575 3650);
FORCENOTE
TOP LAYER
(7950 3650) 0;
DISPLAY LEFT (7950 3650);
DISPLAY 1.042553 (7950 3650);
PAINT PURPLE (7950 3650);
FORCENOTE
5MIL SPACING
(8755 530) 0;
DISPLAY LEFT (8755 530);
DISPLAY 0.808511 (8755 530);
PAINT PURPLE (8755 530);
FORCENOTE
P3V3_STBY _VOLTAGE SENSE
(8580 680) 0;
DISPLAY LEFT (8580 680);
PAINT PURPLE (8580 680);
FORCENOTE
SPOF
(9645 1375) 0;
DISPLAY LEFT (9645 1375);
DISPLAY 2.340426 (9645 1375);
PAINT PURPLE (9645 1375);
FORCENOTE
ROUTE VSENSE_RGND_P3V3_STBY/VSENSE_P3V3_STBY AS DIFF PAIR
(8430 605) 0;
DISPLAY LEFT (8430 605);
DISPLAY 0.808511 (8430 605);
PAINT PURPLE (8430 605);
FORCENOTE
CONNECT AT SINGLE
(10175 1925) 0;
DISPLAY LEFT (10175 1925);
DISPLAY 1.042553 (10175 1925);
PAINT PURPLE (10175 1925);
FORCENOTE
POINT ONLY TOP TO L2
(10125 1875) 0;
DISPLAY LEFT (10125 1875);
DISPLAY 1.042553 (10125 1875);
PAINT PURPLE (10125 1875);
FORCENOTE
IMAX= 27A
(11275 4380) 0;
DISPLAY LEFT (11275 4380);
DISPLAY 0.617021 (11275 4380);
PAINT PURPLE (11275 4380);
FORCENOTE
IOUT DI/DT=1A/US
(11275 4480) 0;
DISPLAY LEFT (11275 4480);
DISPLAY 0.617021 (11275 4480);
PAINT PURPLE (11275 4480);
FORCENOTE
STEP=6A
(11275 4530) 0;
DISPLAY LEFT (11275 4530);
DISPLAY 0.617021 (11275 4530);
PAINT PURPLE (11275 4530);
FORCENOTE
VOUT=3.3V
(11275 4730) 0;
DISPLAY LEFT (11275 4730);
DISPLAY 0.617021 (11275 4730);
PAINT PURPLE (11275 4730);
FORCENOTE
RIPPLE=+-1%
(11275 4630) 0;
DISPLAY LEFT (11275 4630);
DISPLAY 0.617021 (11275 4630);
PAINT PURPLE (11275 4630);
FORCENOTE
SW FREQ=  500 KHZ
(11275 4430) 0;
DISPLAY LEFT (11275 4430);
DISPLAY 0.617021 (11275 4430);
PAINT PURPLE (11275 4430);
FORCENOTE
DC TOLERANCE=+-1.5%
(11275 4680) 0;
DISPLAY LEFT (11275 4680);
DISPLAY 0.617021 (11275 4680);
PAINT PURPLE (11275 4680);
FORCENOTE
AC TOLERANCE & RIPPLE=+/-3.0%
(11275 4580) 0;
DISPLAY LEFT (11275 4580);
DISPLAY 0.617021 (11275 4580);
PAINT PURPLE (11275 4580);
QUIT
